FILE_TYPE = MACRO_DRAWING;
SET COLOR_WIRE YELLOW;
SET COLOR_PROP ORANGE;
SET COLOR_DOT WHITE;
SET COLOR_ARC YELLOW;
SET COLOR_BODY GREEN;
SET COLOR_NOTE PURPLE;
SET PROP_DISPLAY VALUE;
SET PAGE_NUMBER P344;
FORCEADD GND..1
(-3600 2250);
FORCEPROP 3 LASTPIN (-3600 2300) SIG_NAME GND\g
J 0
(-3590 2310);
DISPLAY 0.659574 (-3590 2310);
PAINT MONO (-3590 2310);
DISPLAY INVISIBLE (-3590 2310);
FORCEPROP 2 LAST CDS_LIB pure_quanta_power
J 0
(-3600 2250);
DISPLAY INVISIBLE (-3600 2250);
FORCEPROP 1 LAST SIZE 1B
J 0
(-3525 2200);
DISPLAY 0.872340 (-3525 2200);
PAINT GREEN (-3525 2200);
DISPLAY INVISIBLE (-3525 2200);
FORCEPROP 1 LAST HDL_POWER GND
J 0
(-3600 2400);
DISPLAY 0.872340 (-3600 2400);
PAINT GREEN (-3600 2400);
DISPLAY INVISIBLE (-3600 2400);
FORCEPROP 1 LAST PATH I1
J 0
(-3525 2250);
DISPLAY 0.872340 (-3525 2250);
PAINT AQUA (-3525 2250);
DISPLAY INVISIBLE (-3525 2250);
FORCEADD GND..1
(-3200 2800);
FORCEPROP 3 LASTPIN (-3200 2850) SIG_NAME GND\g
J 0
(-3190 2860);
DISPLAY 0.659574 (-3190 2860);
PAINT MONO (-3190 2860);
DISPLAY INVISIBLE (-3190 2860);
FORCEPROP 2 LAST CDS_LIB pure_quanta_power
J 0
(-3200 2800);
DISPLAY INVISIBLE (-3200 2800);
FORCEPROP 1 LAST SIZE 1B
J 0
(-3125 2750);
DISPLAY 0.872340 (-3125 2750);
PAINT GREEN (-3125 2750);
DISPLAY INVISIBLE (-3125 2750);
FORCEPROP 1 LAST HDL_POWER GND
J 0
(-3200 2950);
DISPLAY 0.872340 (-3200 2950);
PAINT GREEN (-3200 2950);
DISPLAY INVISIBLE (-3200 2950);
FORCEPROP 1 LAST PATH I11
J 0
(-3125 2800);
DISPLAY 0.872340 (-3125 2800);
PAINT AQUA (-3125 2800);
DISPLAY INVISIBLE (-3125 2800);
FORCEADD GND..1
(-2925 3175);
FORCEPROP 3 LASTPIN (-2925 3225) SIG_NAME GND\g
J 0
(-2915 3235);
DISPLAY 0.659574 (-2915 3235);
PAINT MONO (-2915 3235);
DISPLAY INVISIBLE (-2915 3235);
FORCEPROP 2 LAST CDS_LIB pure_quanta_power
J 0
(-2925 3175);
DISPLAY INVISIBLE (-2925 3175);
FORCEPROP 1 LAST SIZE 1B
J 0
(-2850 3125);
DISPLAY 0.872340 (-2850 3125);
PAINT GREEN (-2850 3125);
DISPLAY INVISIBLE (-2850 3125);
FORCEPROP 1 LAST HDL_POWER GND
J 0
(-2925 3325);
DISPLAY 0.872340 (-2925 3325);
PAINT GREEN (-2925 3325);
DISPLAY INVISIBLE (-2925 3325);
FORCEPROP 1 LAST PATH I12
J 0
(-2850 3175);
DISPLAY 0.872340 (-2850 3175);
PAINT AQUA (-2850 3175);
DISPLAY INVISIBLE (-2850 3175);
FORCEADD Q_CAP..1
(-2925 3550);
FORCEPROP 1 LAST LOCATION PC2165
J 0
(-2875 3650);
DISPLAY 0.787234 (-2875 3650);
FORCEPROP 0 LAST $SEC 1
J 0
(-2875 3700);
DISPLAY INVISIBLE (-2875 3700);
FORCEPROP 0 LAST CDS_SEC 1
J 0
(-2875 3700);
DISPLAY INVISIBLE (-2875 3700);
FORCEPROP 1 LASTPIN (-2925 3650) $PN 1
J 0
(-2915 3630);
DISPLAY 0.787234 (-2915 3630);
PAINT MONO (-2915 3630);
DISPLAY INVISIBLE (-2915 3630);
FORCEPROP 1 LASTPIN (-2925 3450) $PN 2
J 0
(-2915 3430);
DISPLAY 0.787234 (-2915 3430);
PAINT MONO (-2915 3430);
DISPLAY INVISIBLE (-2915 3430);
FORCEPROP 1 LAST PACK_TYPE C0402
J 0
(-2875 3450);
DISPLAY 0.638298 (-2875 3450);
FORCEPROP 1 LAST MATERIAL X6S
J 0
(-2875 3500);
DISPLAY 0.638298 (-2875 3500);
PAINT RED (-2875 3500);
FORCEPROP 1 LAST VALUE 1UF
J 0
(-2875 3600);
DISPLAY 0.638298 (-2875 3600);
FORCEPROP 1 LAST VOLTAGE 25V
J 0
(-2875 3550);
DISPLAY 0.638298 (-2875 3550);
FORCEPROP 0 LAST ROOM NIC_P12V_MPS_MAM_BOM2
J 0
(-2900 3725);
DISPLAY 0.446809 (-2900 3725);
PAINT RED (-2900 3725);
FORCEPROP 1 LAST TOLERANCE 10%
J 0
(-2875 3500);
DISPLAY 0.638298 (-2875 3500);
DISPLAY INVISIBLE (-2875 3500);
FORCEPROP 2 LAST CDS_LIB pure_quanta
J 0
(-2925 3550);
DISPLAY INVISIBLE (-2925 3550);
FORCEPROP 1 LAST PATH I13
J 0
(-2875 3700);
DISPLAY 0.978723 (-2875 3700);
PAINT WHITE (-2875 3700);
DISPLAY INVISIBLE (-2875 3700);
FORCEPROP 1 LAST PART_NUMBER CH5104KEB02
J 0
(-2875 3400);
DISPLAY 0.638298 (-2875 3400);
DISPLAY INVISIBLE (-2875 3400);
FORCEADD UNIVERSAL_POWER..1
(-2925 3975);
FORCEPROP 3 LASTPIN (-2925 3925) SIG_NAME P12V_AUX\g
J 0
(-2915 3935);
DISPLAY 0.659574 (-2915 3935);
PAINT MONO (-2915 3935);
DISPLAY INVISIBLE (-2915 3935);
FORCEPROP 1 LAST HDL_POWER P12V_AUX
J 1
(-2925 4025);
DISPLAY 0.872340 (-2925 4025);
PAINT GREEN (-2925 4025);
FORCEPROP 2 LAST CDS_LIB pure_quanta_power
J 0
(-2925 3975);
DISPLAY INVISIBLE (-2925 3975);
FORCEPROP 1 LAST PATH I14
J 0
(-2875 4000);
DISPLAY 0.872340 (-2875 4000);
PAINT AQUA (-2875 4000);
DISPLAY INVISIBLE (-2875 4000);
FORCEADD Q_RES..2
(-1425 2200);
FORCEPROP 1 LAST LOCATION PR3849
J 0
(-1380 2325);
DISPLAY 0.638298 (-1380 2325);
FORCEPROP 0 LAST $SEC 1
J 0
(-1375 2375);
DISPLAY 0.680851 (-1375 2375);
PAINT MONO (-1375 2375);
DISPLAY INVISIBLE (-1375 2375);
FORCEPROP 0 LAST CDS_SEC 1
J 0
(-1375 2375);
DISPLAY 1.021277 (-1375 2375);
DISPLAY INVISIBLE (-1375 2375);
FORCEPROP 1 LASTPIN (-1425 2300) $PN 1
J 0
(-1420 2262);
DISPLAY 0.787234 (-1420 2262);
PAINT MONO (-1420 2262);
FORCEPROP 1 LASTPIN (-1425 2100) $PN 2
J 0
(-1420 2110);
DISPLAY 0.787234 (-1420 2110);
PAINT MONO (-1420 2110);
FORCEPROP 1 LAST VALUE 17.4K
J 0
(-1380 2275);
DISPLAY 0.638298 (-1380 2275);
FORCEPROP 0 LAST ROOM NIC_P12V_MPS_MAM_BOM2
J 0
(-1875 2100);
DISPLAY 0.446809 (-1875 2100);
PAINT RED (-1875 2100);
FORCEPROP 1 LAST MATERIAL CHIP
J 0
(-1385 2125);
DISPLAY 0.638298 (-1385 2125);
PAINT RED (-1385 2125);
FORCEPROP 1 LAST TOLERANCE 1%
J 0
(-1380 2225);
DISPLAY 0.638298 (-1380 2225);
FORCEPROP 1 LAST WATTAGE 1/16W
J 0
(-1385 2175);
DISPLAY 0.638298 (-1385 2175);
FORCEPROP 1 LAST PACK_TYPE 0402LF
J 0
(-1385 2025);
DISPLAY 0.638298 (-1385 2025);
FORCEPROP 2 LAST CDS_LIB pure_quanta
J 0
(-1425 2200);
DISPLAY INVISIBLE (-1425 2200);
FORCEPROP 1 LAST PATH I15
J 0
(-1375 2375);
DISPLAY 0.978723 (-1375 2375);
PAINT WHITE (-1375 2375);
DISPLAY INVISIBLE (-1375 2375);
FORCEPROP 1 LAST PART_NUMBER CS31742FB04
J 0
(-1385 2075);
DISPLAY 0.638298 (-1385 2075);
DISPLAY INVISIBLE (-1385 2075);
FORCEADD GND..1
(-975 1825);
FORCEPROP 3 LASTPIN (-975 1875) SIG_NAME GND\g
J 0
(-965 1885);
DISPLAY 0.659574 (-965 1885);
PAINT MONO (-965 1885);
DISPLAY INVISIBLE (-965 1885);
FORCEPROP 1 LAST SIZE 1B
J 0
(-900 1775);
DISPLAY 0.872340 (-900 1775);
PAINT GREEN (-900 1775);
DISPLAY INVISIBLE (-900 1775);
FORCEPROP 2 LAST CDS_LIB pure_quanta_power
J 0
(-975 1825);
DISPLAY INVISIBLE (-975 1825);
FORCEPROP 1 LAST HDL_POWER GND
J 0
(-975 1975);
DISPLAY 0.872340 (-975 1975);
PAINT GREEN (-975 1975);
DISPLAY INVISIBLE (-975 1975);
FORCEPROP 1 LAST PATH I16
J 0
(-900 1825);
DISPLAY 0.872340 (-900 1825);
PAINT AQUA (-900 1825);
DISPLAY INVISIBLE (-900 1825);
FORCEADD Q_RES..1
(-850 2550);
FORCEPROP 1 LAST LOCATION PR3851
J 0
(-925 2600);
DISPLAY 0.638298 (-925 2600);
FORCEPROP 0 LAST $SEC 1
J 0
(-975 2600);
DISPLAY 0.680851 (-975 2600);
PAINT MONO (-975 2600);
DISPLAY INVISIBLE (-975 2600);
FORCEPROP 0 LAST CDS_SEC 1
J 0
(-1150 2675);
DISPLAY INVISIBLE (-1150 2675);
FORCEPROP 1 LASTPIN (-950 2550) $PN 1
J 0
(-938 2562);
DISPLAY 0.787234 (-938 2562);
PAINT MONO (-938 2562);
DISPLAY INVISIBLE (-938 2562);
FORCEPROP 1 LASTPIN (-750 2550) $PN 2
J 0
(-788 2562);
DISPLAY 0.787234 (-788 2562);
PAINT MONO (-788 2562);
DISPLAY INVISIBLE (-788 2562);
FORCEPROP 0 LAST ROOM NIC_P12V_MPS_MAM_BOM2
J 0
(-700 2500);
DISPLAY 0.446809 (-700 2500);
PAINT RED (-700 2500);
FORCEPROP 1 LAST WATTAGE 1/16W
J 2
(-850 2475);
DISPLAY 0.510638 (-850 2475);
FORCEPROP 1 LAST VALUE 10K
J 2
(-850 2500);
DISPLAY 0.510638 (-850 2500);
FORCEPROP 1 LAST TOLERANCE 1%
J 0
(-825 2500);
DISPLAY 0.510638 (-825 2500);
FORCEPROP 1 LAST MATERIAL CHIP
J 0
(-825 2475);
DISPLAY 0.510638 (-825 2475);
PAINT RED (-825 2475);
FORCEPROP 1 LAST PACK_TYPE 0402LF
J 0
(-725 2525);
DISPLAY 0.510638 (-725 2525);
FORCEPROP 2 LAST CDS_LIB pure_quanta
J 0
(-850 2550);
DISPLAY INVISIBLE (-850 2550);
FORCEPROP 1 LAST PATH I18
J 0
(-900 2700);
DISPLAY 0.978723 (-900 2700);
PAINT WHITE (-900 2700);
DISPLAY INVISIBLE (-900 2700);
FORCEPROP 1 LAST PART_NUMBER CS31002FB08
J 0
(-975 2575);
DISPLAY 0.510638 (-975 2575);
DISPLAY INVISIBLE (-975 2575);
FORCEADD VCCAUX15..1
(-580 2608);
FORCEPROP 3 LASTPIN (-580 2558) SIG_NAME P3V3_AUX\g
J 0
(-570 2568);
DISPLAY 0.659574 (-570 2568);
PAINT MONO (-570 2568);
DISPLAY INVISIBLE (-570 2568);
FORCEPROP 1 LAST HDL_POWER P3V3_AUX
J 1
(-550 2650);
DISPLAY 0.723404 (-550 2650);
PAINT GREEN (-550 2650);
FORCEPROP 2 LAST CDS_LIB pure_quanta_power
J 0
(-580 2608);
DISPLAY INVISIBLE (-580 2608);
FORCEPROP 1 LAST PATH I19
J 0
(-530 2633);
DISPLAY 0.872340 (-530 2633);
PAINT AQUA (-530 2633);
DISPLAY INVISIBLE (-530 2633);
FORCEADD Q_CAP..1
(-3600 2600);
FORCEPROP 1 LAST LOCATION PC2164
J 0
(-3550 2700);
DISPLAY 0.808511 (-3550 2700);
FORCEPROP 0 LAST $SEC 1
J 0
(-3530 2758);
DISPLAY INVISIBLE (-3530 2758);
FORCEPROP 0 LAST CDS_SEC 1
J 0
(-3530 2758);
DISPLAY INVISIBLE (-3530 2758);
FORCEPROP 1 LASTPIN (-3600 2700) $PN 1
J 0
(-3590 2680);
DISPLAY 0.787234 (-3590 2680);
PAINT MONO (-3590 2680);
DISPLAY INVISIBLE (-3590 2680);
FORCEPROP 1 LASTPIN (-3600 2500) $PN 2
J 0
(-3590 2480);
DISPLAY 0.787234 (-3590 2480);
PAINT MONO (-3590 2480);
DISPLAY INVISIBLE (-3590 2480);
FORCEPROP 0 LAST ROOM NIC_P12V_MPS_MAM_BOM2
J 0
(-3675 2400);
DISPLAY 0.446809 (-3675 2400);
PAINT RED (-3675 2400);
FORCEPROP 1 LAST PACK_TYPE 0402
J 0
(-3555 2508);
DISPLAY 0.638298 (-3555 2508);
FORCEPROP 1 LAST VALUE 0.22UF
J 0
(-3550 2650);
DISPLAY 0.638298 (-3550 2650);
FORCEPROP 1 LAST VOLTAGE 16V
J 0
(-3550 2600);
DISPLAY 0.638298 (-3550 2600);
FORCEPROP 1 LAST MATERIAL X7R
J 0
(-3555 2558);
DISPLAY 0.638298 (-3555 2558);
PAINT RED (-3555 2558);
FORCEPROP 1 LAST TOLERANCE 10%
J 0
(-3550 2550);
DISPLAY 0.638298 (-3550 2550);
DISPLAY INVISIBLE (-3550 2550);
FORCEPROP 2 LAST CDS_LIB pure_quanta
J 0
(-3600 2600);
DISPLAY INVISIBLE (-3600 2600);
FORCEPROP 1 LAST PATH I2
J 0
(-3550 2750);
DISPLAY 0.978723 (-3550 2750);
PAINT WHITE (-3550 2750);
DISPLAY INVISIBLE (-3550 2750);
FORCEPROP 1 LAST PART_NUMBER CH4223K1B00
J 0
(-3550 2450);
DISPLAY 0.638298 (-3550 2450);
DISPLAY INVISIBLE (-3550 2450);
FORCEADD Q_RES..2
(20 2533);
FORCEPROP 1 LAST LOCATION PR3854
J 0
(65 2658);
DISPLAY 0.638298 (65 2658);
FORCEPROP 0 LAST $SEC 1
J 0
(70 2708);
DISPLAY INVISIBLE (70 2708);
FORCEPROP 0 LAST CDS_SEC 1
J 0
(70 2708);
DISPLAY INVISIBLE (70 2708);
FORCEPROP 1 LASTPIN (20 2633) $PN 1
J 0
(25 2595);
DISPLAY 0.787234 (25 2595);
PAINT MONO (25 2595);
DISPLAY INVISIBLE (25 2595);
FORCEPROP 1 LASTPIN (20 2433) $PN 2
J 0
(25 2443);
DISPLAY 0.787234 (25 2443);
PAINT MONO (25 2443);
DISPLAY INVISIBLE (25 2443);
FORCEPROP 1 LAST PACK_TYPE 0402LF
J 0
(60 2358);
DISPLAY 0.638298 (60 2358);
FORCEPROP 0 LAST ROOM NIC_P12V_MPS_MAM_BOM2
J 0
(75 2325);
DISPLAY 0.446809 (75 2325);
PAINT RED (75 2325);
FORCEPROP 1 LAST MATERIAL CHIP
J 0
(60 2458);
DISPLAY 0.638298 (60 2458);
PAINT RED (60 2458);
FORCEPROP 1 LAST WATTAGE 1/16W
J 0
(60 2508);
DISPLAY 0.638298 (60 2508);
FORCEPROP 1 LAST TOLERANCE 1%
J 0
(65 2558);
DISPLAY 0.638298 (65 2558);
FORCEPROP 1 LAST VALUE 10K
J 0
(65 2608);
DISPLAY 0.638298 (65 2608);
FORCEPROP 2 LAST CDS_LIB pure_quanta
J 0
(20 2533);
DISPLAY INVISIBLE (20 2533);
FORCEPROP 1 LAST PATH I20
J 0
(70 2708);
DISPLAY 0.978723 (70 2708);
PAINT WHITE (70 2708);
DISPLAY INVISIBLE (70 2708);
FORCEPROP 1 LAST PART_NUMBER CS31002FB08
J 0
(60 2408);
DISPLAY 0.638298 (60 2408);
DISPLAY INVISIBLE (60 2408);
FORCEADD GND..1
(220 2208);
FORCEPROP 3 LASTPIN (220 2258) SIG_NAME GND\g
J 0
(230 2268);
DISPLAY 0.659574 (230 2268);
PAINT MONO (230 2268);
DISPLAY INVISIBLE (230 2268);
FORCEPROP 1 LAST SIZE 1B
J 0
(295 2158);
DISPLAY 0.872340 (295 2158);
PAINT GREEN (295 2158);
DISPLAY INVISIBLE (295 2158);
FORCEPROP 2 LAST CDS_LIB pure_quanta_power
J 0
(220 2208);
DISPLAY INVISIBLE (220 2208);
FORCEPROP 1 LAST HDL_POWER GND
J 0
(220 2358);
DISPLAY 0.872340 (220 2358);
PAINT GREEN (220 2358);
DISPLAY INVISIBLE (220 2358);
FORCEPROP 1 LAST PATH I21
J 0
(295 2208);
DISPLAY 0.872340 (295 2208);
PAINT AQUA (295 2208);
DISPLAY INVISIBLE (295 2208);
FORCEADD Q_RES..1
(425 1950);
FORCEPROP 1 LAST LOCATION R3874
J 0
(250 1950);
DISPLAY 0.510638 (250 1950);
FORCEPROP 0 LAST $SEC 1
J 0
(375 2050);
DISPLAY 0.680851 (375 2050);
PAINT MONO (375 2050);
DISPLAY INVISIBLE (375 2050);
FORCEPROP 0 LAST CDS_SEC 1
J 0
(375 2050);
DISPLAY 1.021277 (375 2050);
DISPLAY INVISIBLE (375 2050);
FORCEPROP 1 LASTPIN (325 1950) $PN 1
J 0
(337 1962);
DISPLAY 0.787234 (337 1962);
PAINT MONO (337 1962);
FORCEPROP 1 LASTPIN (525 1950) $PN 2
J 0
(487 1962);
DISPLAY 0.787234 (487 1962);
PAINT MONO (487 1962);
FORCEPROP 0 LAST ROOM NIC_P12V_MPS_TIC_BOM3
J 0
(125 1825);
DISPLAY 0.680851 (125 1825);
PAINT RED (125 1825);
FORCEPROP 1 LAST PACK_TYPE 0402LF
J 0
(575 1900);
DISPLAY 0.595745 (575 1900);
FORCEPROP 1 LAST TOLERANCE 5%
J 0
(600 1950);
DISPLAY 0.595745 (600 1950);
FORCEPROP 1 LAST VALUE 0
J 2
(575 1950);
DISPLAY 0.595745 (575 1950);
FORCEPROP 1 LAST MATERIAL EMPTY
J 0
(50 1950);
DISPLAY 0.595745 (50 1950);
PAINT RED (50 1950);
FORCEPROP 1 LAST WATTAGE 1/16W
J 2
(225 1900);
DISPLAY 0.595745 (225 1900);
FORCEPROP 2 LAST CDS_LIB pure_quanta
J 0
(425 1950);
DISPLAY INVISIBLE (425 1950);
FORCEPROP 1 LAST PATH I22
J 0
(375 2100);
DISPLAY 0.978723 (375 2100);
PAINT WHITE (375 2100);
DISPLAY INVISIBLE (375 2100);
FORCEPROP 1 LAST PART_NUMBER CS00002JB13
J 0
(250 1900);
DISPLAY 0.595745 (250 1900);
DISPLAY INVISIBLE (250 1900);
FORCEADD Q_RES..1
(425 2075);
FORCEPROP 1 LAST LOCATION R3873
J 0
(250 2075);
DISPLAY 0.510638 (250 2075);
FORCEPROP 0 LAST $SEC 1
J 0
(375 2175);
DISPLAY 0.680851 (375 2175);
PAINT MONO (375 2175);
DISPLAY INVISIBLE (375 2175);
FORCEPROP 0 LAST CDS_SEC 1
J 0
(375 2175);
DISPLAY 1.021277 (375 2175);
DISPLAY INVISIBLE (375 2175);
FORCEPROP 1 LASTPIN (325 2075) $PN 1
J 0
(337 2087);
DISPLAY 0.787234 (337 2087);
PAINT MONO (337 2087);
FORCEPROP 1 LASTPIN (525 2075) $PN 2
J 0
(487 2087);
DISPLAY 0.787234 (487 2087);
PAINT MONO (487 2087);
FORCEPROP 1 LAST WATTAGE 1/16W
J 2
(225 2025);
DISPLAY 0.595745 (225 2025);
FORCEPROP 1 LAST PACK_TYPE 0402LF
J 0
(575 2025);
DISPLAY 0.595745 (575 2025);
FORCEPROP 1 LAST TOLERANCE 5%
J 0
(600 2075);
DISPLAY 0.595745 (600 2075);
FORCEPROP 0 LAST ROOM NIC_P12V_MPS_MAM_BOM2
J 0
(175 2150);
DISPLAY 0.553191 (175 2150);
PAINT RED (175 2150);
FORCEPROP 1 LAST VALUE 0
J 2
(575 2075);
DISPLAY 0.595745 (575 2075);
FORCEPROP 1 LAST MATERIAL CHIP
J 0
(50 2075);
DISPLAY 0.595745 (50 2075);
PAINT RED (50 2075);
FORCEPROP 2 LAST CDS_LIB pure_quanta
J 0
(425 2075);
DISPLAY INVISIBLE (425 2075);
FORCEPROP 1 LAST PATH I23
J 0
(375 2225);
DISPLAY 0.978723 (375 2225);
PAINT WHITE (375 2225);
DISPLAY INVISIBLE (375 2225);
FORCEPROP 1 LAST PART_NUMBER CS00002JB13
J 0
(250 2025);
DISPLAY 0.595745 (250 2025);
DISPLAY INVISIBLE (250 2025);
FORCEADD Q_CAP..1
(550 2525);
FORCEPROP 1 LAST LOCATION PC1320
J 0
(600 2625);
DISPLAY 0.638298 (600 2625);
FORCEPROP 0 LAST $SEC 1
J 0
(600 2675);
DISPLAY INVISIBLE (600 2675);
FORCEPROP 0 LAST CDS_SEC 1
J 0
(600 2675);
DISPLAY INVISIBLE (600 2675);
FORCEPROP 1 LASTPIN (550 2625) $PN 1
J 0
(560 2605);
DISPLAY 0.787234 (560 2605);
PAINT MONO (560 2605);
DISPLAY INVISIBLE (560 2605);
FORCEPROP 1 LASTPIN (550 2425) $PN 2
J 0
(560 2405);
DISPLAY 0.787234 (560 2405);
PAINT MONO (560 2405);
DISPLAY INVISIBLE (560 2405);
FORCEPROP 0 LAST ROOM NIC_P12V_MPS_MAM_BOM2
J 0
(600 2275);
DISPLAY 0.446809 (600 2275);
PAINT RED (600 2275);
FORCEPROP 1 LAST PACK_TYPE C0603
J 0
(600 2325);
DISPLAY 0.638298 (600 2325);
FORCEPROP 1 LAST MATERIAL X7R
J 0
(600 2425);
DISPLAY 0.638298 (600 2425);
PAINT RED (600 2425);
FORCEPROP 1 LAST VALUE 2.2UF
J 0
(600 2575);
DISPLAY 0.638298 (600 2575);
FORCEPROP 1 LAST VOLTAGE 16V
J 0
(600 2525);
DISPLAY 0.638298 (600 2525);
FORCEPROP 1 LAST TOLERANCE 20%
J 0
(600 2475);
DISPLAY 0.638298 (600 2475);
FORCEPROP 2 LAST CDS_LIB pure_quanta
J 0
(550 2525);
DISPLAY INVISIBLE (550 2525);
FORCEPROP 1 LAST PATH I24
J 0
(600 2675);
DISPLAY 0.978723 (600 2675);
PAINT WHITE (600 2675);
DISPLAY INVISIBLE (600 2675);
FORCEPROP 1 LAST PART_NUMBER CH5223M1900
J 0
(600 2375);
DISPLAY 0.638298 (600 2375);
DISPLAY INVISIBLE (600 2375);
FORCEADD OFFPAGE..2
(1675 2075);
PAINT AQUA (1675 2075);
FORCEPROP 2 LAST $XR0 258 
J 0
(1864 2075);
DISPLAY 0.638298 (1864 2075);
PAINT MONO (1864 2075);
FORCEPROP 2 LAST CDS_LIB standard
J 0
(1675 2075);
DISPLAY INVISIBLE (1675 2075);
FORCEPROP 1 LAST OFFPAGE TRUE
J 0
(2000 1950);
DISPLAY 0.872340 (2000 1950);
PAINT AQUA (2000 1950);
DISPLAY INVISIBLE (2000 1950);
FORCEPROP 1 LAST COMMENT_BODY TRUE
J 0
(1630 1980);
DISPLAY 0.872340 (1630 1980);
PAINT GREEN (1630 1980);
DISPLAY INVISIBLE (1630 1980);
FORCEPROP 2 LAST PATH I25
J 0
(1875 2125);
DISPLAY 1.021277 (1875 2125);
DISPLAY INVISIBLE (1875 2125);
FORCEADD OFFPAGE..2
(1675 1950);
PAINT AQUA (1675 1950);
FORCEPROP 2 LAST $XR0 258 
J 0
(1864 1950);
DISPLAY 0.638298 (1864 1950);
PAINT MONO (1864 1950);
FORCEPROP 2 LAST CDS_LIB standard
J 0
(1675 1950);
DISPLAY INVISIBLE (1675 1950);
FORCEPROP 1 LAST OFFPAGE TRUE
J 0
(2000 1825);
DISPLAY 0.872340 (2000 1825);
PAINT AQUA (2000 1825);
DISPLAY INVISIBLE (2000 1825);
FORCEPROP 1 LAST COMMENT_BODY TRUE
J 0
(1630 1855);
DISPLAY 0.872340 (1630 1855);
PAINT GREEN (1630 1855);
DISPLAY INVISIBLE (1630 1855);
FORCEPROP 2 LAST PATH I26
J 0
(1875 2000);
DISPLAY 1.021277 (1875 2000);
DISPLAY INVISIBLE (1875 2000);
FORCEADD Q_RES..2
(-1475 3600);
FORCEPROP 1 LAST LOCATION R3848
J 0
(-1425 3775);
DISPLAY 0.510638 (-1425 3775);
FORCEPROP 0 LAST $SEC 1
J 0
(-1425 3800);
DISPLAY 0.680851 (-1425 3800);
PAINT MONO (-1425 3800);
DISPLAY INVISIBLE (-1425 3800);
FORCEPROP 0 LAST CDS_SEC 1
J 0
(-1425 3750);
DISPLAY INVISIBLE (-1425 3750);
FORCEPROP 1 LASTPIN (-1475 3700) $PN 1
J 0
(-1470 3662);
DISPLAY 0.787234 (-1470 3662);
PAINT MONO (-1470 3662);
FORCEPROP 1 LASTPIN (-1475 3500) $PN 2
J 0
(-1470 3510);
DISPLAY 0.787234 (-1470 3510);
PAINT MONO (-1470 3510);
FORCEPROP 1 LAST PACK_TYPE 0402LF
J 0
(-1430 3475);
DISPLAY 0.510638 (-1430 3475);
FORCEPROP 1 LAST VALUE 10K
J 0
(-1425 3725);
DISPLAY 0.510638 (-1425 3725);
FORCEPROP 1 LAST MATERIAL CHIP
J 0
(-1430 3575);
DISPLAY 0.510638 (-1430 3575);
PAINT RED (-1430 3575);
FORCEPROP 0 LAST ROOM NIC_P12V_MPS_MAM_BOM2
J 0
(-1425 3825);
DISPLAY 0.553191 (-1425 3825);
PAINT RED (-1425 3825);
FORCEPROP 1 LAST WATTAGE 1/16W
J 0
(-1430 3625);
DISPLAY 0.510638 (-1430 3625);
FORCEPROP 1 LAST TOLERANCE 1%
J 0
(-1425 3675);
DISPLAY 0.510638 (-1425 3675);
FORCEPROP 2 LAST CDS_LIB pure_quanta
J 0
(-1475 3600);
DISPLAY INVISIBLE (-1475 3600);
FORCEPROP 1 LAST PATH I27
J 0
(-1425 3775);
DISPLAY 0.978723 (-1425 3775);
PAINT WHITE (-1425 3775);
DISPLAY INVISIBLE (-1425 3775);
FORCEPROP 1 LAST PART_NUMBER CS31002FB08
J 0
(-1430 3525);
DISPLAY 0.510638 (-1430 3525);
DISPLAY INVISIBLE (-1430 3525);
FORCEADD VCCAUX15..1
(-1475 3825);
FORCEPROP 3 LASTPIN (-1475 3775) SIG_NAME P3V3_AUX\g
J 0
(-1465 3785);
DISPLAY 0.659574 (-1465 3785);
PAINT MONO (-1465 3785);
DISPLAY INVISIBLE (-1465 3785);
FORCEPROP 1 LAST HDL_POWER P3V3_AUX
J 1
(-1475 3875);
DISPLAY 0.723404 (-1475 3875);
PAINT GREEN (-1475 3875);
FORCEPROP 2 LAST CDS_LIB pure_quanta_power
J 0
(-1475 3825);
DISPLAY INVISIBLE (-1475 3825);
FORCEPROP 1 LAST PATH I28
J 0
(-1425 3850);
DISPLAY 0.872340 (-1425 3850);
PAINT AQUA (-1425 3850);
DISPLAY INVISIBLE (-1425 3850);
FORCEADD OFFPAGE..1
R 2
(-775 2800);
PAINT AQUA (-775 2800);
FORCEPROP 2 LAST $XR0 141 
J 0
(-589 2800);
DISPLAY 0.638298 (-589 2800);
PAINT MONO (-589 2800);
FORCEPROP 2 LAST CDS_LIB standard
J 2
(-775 2800);
DISPLAY INVISIBLE (-775 2800);
FORCEPROP 1 LAST OFFPAGE TRUE
J 2
(-1100 2675);
DISPLAY 0.872340 (-1100 2675);
PAINT AQUA (-1100 2675);
DISPLAY INVISIBLE (-1100 2675);
FORCEPROP 1 LAST COMMENT_BODY TRUE
J 2
(-900 2700);
DISPLAY 0.872340 (-900 2700);
PAINT GREEN (-900 2700);
DISPLAY INVISIBLE (-900 2700);
FORCEPROP 2 LAST PATH I29
J 0
(-575 2850);
DISPLAY 1.021277 (-575 2850);
DISPLAY INVISIBLE (-575 2850);
FORCEADD GND..1
(-3175 2175);
FORCEPROP 3 LASTPIN (-3175 2225) SIG_NAME GND\g
J 0
(-3165 2235);
DISPLAY 0.659574 (-3165 2235);
PAINT MONO (-3165 2235);
DISPLAY INVISIBLE (-3165 2235);
FORCEPROP 1 LAST SIZE 1B
J 0
(-3100 2125);
DISPLAY 0.872340 (-3100 2125);
PAINT GREEN (-3100 2125);
DISPLAY INVISIBLE (-3100 2125);
FORCEPROP 2 LAST CDS_LIB pure_quanta_power
J 0
(-3175 2175);
DISPLAY INVISIBLE (-3175 2175);
FORCEPROP 1 LAST HDL_POWER GND
J 0
(-3175 2325);
DISPLAY 0.872340 (-3175 2325);
PAINT GREEN (-3175 2325);
DISPLAY INVISIBLE (-3175 2325);
FORCEPROP 1 LAST PATH I3
J 0
(-3100 2175);
DISPLAY 0.872340 (-3100 2175);
PAINT AQUA (-3100 2175);
DISPLAY INVISIBLE (-3100 2175);
FORCEADD Q_RES..2
(-925 3025);
FORCEPROP 1 LAST LOCATION PR3850
J 0
(-880 3150);
DISPLAY 0.978723 (-880 3150);
FORCEPROP 0 LAST $SEC 1
J 0
(-875 3200);
DISPLAY 0.680851 (-875 3200);
PAINT MONO (-875 3200);
DISPLAY INVISIBLE (-875 3200);
FORCEPROP 0 LAST CDS_SEC 1
J 0
(-875 3200);
DISPLAY 1.021277 (-875 3200);
DISPLAY INVISIBLE (-875 3200);
FORCEPROP 1 LASTPIN (-925 3125) $PN 1
J 0
(-920 3087);
DISPLAY 0.787234 (-920 3087);
PAINT MONO (-920 3087);
FORCEPROP 1 LASTPIN (-925 2925) $PN 2
J 0
(-920 2935);
DISPLAY 0.787234 (-920 2935);
PAINT MONO (-920 2935);
FORCEPROP 0 LAST ROOM NIC_P12V_MPS_MAM_BOM2
J 0
(-875 3225);
DISPLAY 0.446809 (-875 3225);
PAINT RED (-875 3225);
FORCEPROP 1 LAST PACK_TYPE 0402LF
J 0
(-885 2900);
DISPLAY 0.510638 (-885 2900);
FORCEPROP 1 LAST MATERIAL EMPTY
J 0
(-885 2950);
DISPLAY 0.510638 (-885 2950);
PAINT RED (-885 2950);
FORCEPROP 1 LAST VALUE 100
J 0
(-880 3100);
DISPLAY 0.510638 (-880 3100);
FORCEPROP 1 LAST WATTAGE 1/16W
J 0
(-885 3000);
DISPLAY 0.510638 (-885 3000);
FORCEPROP 1 LAST TOLERANCE 1%
J 0
(-880 3050);
DISPLAY 0.510638 (-880 3050);
FORCEPROP 2 LAST CDS_LIB pure_quanta
J 0
(-925 3025);
DISPLAY INVISIBLE (-925 3025);
FORCEPROP 1 LAST PATH I30
J 0
(-875 3200);
DISPLAY 0.978723 (-875 3200);
PAINT WHITE (-875 3200);
DISPLAY INVISIBLE (-875 3200);
FORCEPROP 1 LAST PART_NUMBER CS11002FB07
J 0
(-885 2850);
DISPLAY 0.510638 (-885 2850);
DISPLAY INVISIBLE (-885 2850);
FORCEADD Q_RES..2
(-375 3025);
FORCEPROP 1 LAST LOCATION PR3852
J 0
(-350 3100);
DISPLAY 0.723404 (-350 3100);
PAINT AQUA (-350 3100);
FORCEPROP 0 LAST $SEC 1
J 0
(-350 3150);
DISPLAY 0.680851 (-350 3150);
PAINT MONO (-350 3150);
DISPLAY INVISIBLE (-350 3150);
FORCEPROP 0 LAST CDS_SEC 1
J 0
(-350 3150);
DISPLAY 1.021277 (-350 3150);
DISPLAY INVISIBLE (-350 3150);
FORCEPROP 1 LASTPIN (-375 3125) $PN 1
J 0
(-370 3087);
DISPLAY 0.787234 (-370 3087);
PAINT MONO (-370 3087);
FORCEPROP 1 LASTPIN (-375 2925) $PN 2
J 0
(-370 2935);
DISPLAY 0.787234 (-370 2935);
PAINT MONO (-370 2935);
FORCEPROP 1 LAST MATERIAL EMPTY
J 0
(-350 2850);
DISPLAY 0.723404 (-350 2850);
PAINT RED (-350 2850);
FORCEPROP 1 LAST PACK_TYPE 0402LF
J 0
(-350 2950);
DISPLAY 0.574468 (-350 2950);
PAINT SKYBLUE (-350 2950);
FORCEPROP 1 LAST TOLERANCE 1%
J 0
(-350 3000);
DISPLAY 0.574468 (-350 3000);
PAINT SKYBLUE (-350 3000);
FORCEPROP 1 LAST VALUE 71.5K
J 0
(-350 3050);
DISPLAY 0.574468 (-350 3050);
PAINT SKYBLUE (-350 3050);
FORCEPROP 0 LAST ROOM NIC_P12V_MPS_MAM_BOM2
J 0
(-350 3200);
DISPLAY 0.446809 (-350 3200);
PAINT RED (-350 3200);
FORCEPROP 1 LAST WATTAGE 1/16W
J 0
(-350 3000);
DISPLAY 0.723404 (-350 3000);
PAINT SKYBLUE (-350 3000);
DISPLAY INVISIBLE (-350 3000);
FORCEPROP 2 LAST CDS_LIB pure_quanta
J 0
(-375 3025);
DISPLAY INVISIBLE (-375 3025);
FORCEPROP 1 LAST PATH I31
J 0
(-325 3200);
DISPLAY 0.978723 (-325 3200);
PAINT WHITE (-325 3200);
DISPLAY INVISIBLE (-325 3200);
FORCEPROP 1 LAST PART_NUMBER CS37152FB05
J 0
(-350 2900);
DISPLAY 0.468085 (-350 2900);
PAINT WHITE (-350 2900);
DISPLAY INVISIBLE (-350 2900);
FORCEADD OFFPAGE..2
(-675 3400);
PAINT AQUA (-675 3400);
FORCEPROP 2 LAST $XR3 248 
J 0
(-126 3400);
DISPLAY 0.638298 (-126 3400);
PAINT MONO (-126 3400);
FORCEPROP 2 LAST $XR1 141 
J 0
(-366 3400);
DISPLAY 0.638298 (-366 3400);
PAINT MONO (-366 3400);
FORCEPROP 2 LAST $XR0 140 
J 0
(-486 3400);
DISPLAY 0.638298 (-486 3400);
PAINT MONO (-486 3400);
FORCEPROP 2 LAST $XR2 142 
J 0
(-246 3400);
DISPLAY 0.638298 (-246 3400);
PAINT MONO (-246 3400);
FORCEPROP 2 LAST CDS_LIB standard
J 0
(-675 3400);
DISPLAY INVISIBLE (-675 3400);
FORCEPROP 1 LAST OFFPAGE TRUE
J 0
(-350 3275);
DISPLAY 0.872340 (-350 3275);
PAINT AQUA (-350 3275);
DISPLAY INVISIBLE (-350 3275);
FORCEPROP 1 LAST COMMENT_BODY TRUE
J 0
(-720 3305);
DISPLAY 0.872340 (-720 3305);
PAINT GREEN (-720 3305);
DISPLAY INVISIBLE (-720 3305);
FORCEPROP 2 LAST PATH I32
J 0
(-350 3450);
DISPLAY 1.021277 (-350 3450);
DISPLAY INVISIBLE (-350 3450);
FORCEADD OFFPAGE..1
(-1150 6475);
PAINT AQUA (-1150 6475);
FORCEPROP 2 LAST $XR3 248 
J 0
(-1701 6475);
DISPLAY 0.638298 (-1701 6475);
PAINT MONO (-1701 6475);
FORCEPROP 2 LAST $XR2 140 
J 0
(-1581 6475);
DISPLAY 0.638298 (-1581 6475);
PAINT MONO (-1581 6475);
FORCEPROP 2 LAST $XR1 83 
J 0
(-1461 6475);
DISPLAY 0.638298 (-1461 6475);
PAINT MONO (-1461 6475);
FORCEPROP 2 LAST $XR0 81 
J 0
(-1371 6475);
DISPLAY 0.638298 (-1371 6475);
PAINT MONO (-1371 6475);
FORCEPROP 2 LAST CDS_LIB standard
J 0
(-1150 6475);
DISPLAY INVISIBLE (-1150 6475);
FORCEPROP 1 LAST OFFPAGE TRUE
J 0
(-825 6350);
DISPLAY 0.872340 (-825 6350);
PAINT AQUA (-825 6350);
DISPLAY INVISIBLE (-825 6350);
FORCEPROP 1 LAST COMMENT_BODY TRUE
J 0
(-1025 6375);
DISPLAY 0.872340 (-1025 6375);
PAINT GREEN (-1025 6375);
DISPLAY INVISIBLE (-1025 6375);
FORCEPROP 2 LAST PATH I33
J 0
(-1400 6525);
DISPLAY 1.021277 (-1400 6525);
DISPLAY INVISIBLE (-1400 6525);
FORCEADD UNIVERSAL_GND..1
(-250 5875);
FORCEPROP 3 LASTPIN (-250 5925) SIG_NAME GND\g
J 0
(-240 5935);
DISPLAY 0.659574 (-240 5935);
PAINT MONO (-240 5935);
DISPLAY INVISIBLE (-240 5935);
FORCEPROP 2 LAST CDS_LIB pure_quanta_power
J 0
(-250 5875);
DISPLAY INVISIBLE (-250 5875);
FORCEPROP 1 LAST HDL_POWER GND
J 1
(-225 5800);
DISPLAY 0.872340 (-225 5800);
PAINT GREEN (-225 5800);
DISPLAY INVISIBLE (-225 5800);
FORCEPROP 1 LAST PATH I34
J 0
(-175 5875);
DISPLAY 0.872340 (-175 5875);
PAINT AQUA (-175 5875);
DISPLAY INVISIBLE (-175 5875);
FORCEADD Q_CAP..1
(-250 6175);
FORCEPROP 1 LAST LOCATION PC2168
J 0
(-200 6250);
DISPLAY 0.723404 (-200 6250);
PAINT AQUA (-200 6250);
FORCEPROP 0 LAST $SEC 1
J 0
(-200 6300);
DISPLAY INVISIBLE (-200 6300);
FORCEPROP 0 LAST CDS_SEC 1
J 0
(-200 6300);
DISPLAY INVISIBLE (-200 6300);
FORCEPROP 1 LASTPIN (-250 6275) $PN 1
J 0
(-240 6255);
DISPLAY 0.787234 (-240 6255);
PAINT MONO (-240 6255);
DISPLAY INVISIBLE (-240 6255);
FORCEPROP 1 LASTPIN (-250 6075) $PN 2
J 0
(-240 6055);
DISPLAY 0.787234 (-240 6055);
PAINT MONO (-240 6055);
DISPLAY INVISIBLE (-240 6055);
FORCEPROP 0 LAST ROOM NIC_P3V3_BOM2
J 0
(-200 5975);
DISPLAY 0.553191 (-200 5975);
PAINT RED (-200 5975);
FORCEPROP 1 LAST VALUE 39PF
J 0
(-200 6200);
DISPLAY 0.574468 (-200 6200);
PAINT SKYBLUE (-200 6200);
FORCEPROP 1 LAST MATERIAL NPO
J 0
(-200 6150);
DISPLAY 0.574468 (-200 6150);
PAINT RED (-200 6150);
FORCEPROP 1 LAST VOLTAGE 50V
J 0
(-200 6125);
DISPLAY 0.574468 (-200 6125);
PAINT SKYBLUE (-200 6125);
FORCEPROP 1 LAST PACK_TYPE 0402
J 0
(-200 6075);
DISPLAY 0.574468 (-200 6075);
PAINT SKYBLUE (-200 6075);
FORCEPROP 2 LAST CDS_LIB pure_quanta
J 0
(-250 6175);
DISPLAY INVISIBLE (-250 6175);
FORCEPROP 1 LAST TOLERANCE 5%
J 0
(-200 6125);
DISPLAY 0.723404 (-200 6125);
PAINT SKYBLUE (-200 6125);
DISPLAY INVISIBLE (-200 6125);
FORCEPROP 1 LAST PATH I35
J 0
(-200 6325);
DISPLAY 0.978723 (-200 6325);
PAINT WHITE (-200 6325);
DISPLAY INVISIBLE (-200 6325);
FORCEPROP 1 LAST PART_NUMBER CH03906JB06
J 0
(-200 6025);
DISPLAY 0.574468 (-200 6025);
PAINT WHITE (-200 6025);
DISPLAY INVISIBLE (-200 6025);
FORCEADD Q_RES..2
(20 2958);
FORCEPROP 1 LAST LOCATION PR3853
J 0
(65 3083);
DISPLAY 0.638298 (65 3083);
FORCEPROP 0 LAST $SEC 1
J 0
(70 3133);
DISPLAY INVISIBLE (70 3133);
FORCEPROP 0 LAST CDS_SEC 1
J 0
(70 3133);
DISPLAY INVISIBLE (70 3133);
FORCEPROP 1 LASTPIN (20 3058) $PN 1
J 0
(25 3020);
DISPLAY 0.787234 (25 3020);
PAINT MONO (25 3020);
DISPLAY INVISIBLE (25 3020);
FORCEPROP 1 LASTPIN (20 2858) $PN 2
J 0
(25 2868);
DISPLAY 0.787234 (25 2868);
PAINT MONO (25 2868);
DISPLAY INVISIBLE (25 2868);
FORCEPROP 1 LAST PACK_TYPE 0402LF
J 0
(60 2783);
DISPLAY 0.638298 (60 2783);
FORCEPROP 1 LAST WATTAGE 1/16W
J 0
(60 2933);
DISPLAY 0.638298 (60 2933);
FORCEPROP 1 LAST MATERIAL CHIP
J 0
(60 2883);
DISPLAY 0.638298 (60 2883);
PAINT RED (60 2883);
FORCEPROP 1 LAST VALUE 120K
J 0
(65 3033);
DISPLAY 0.638298 (65 3033);
FORCEPROP 1 LAST TOLERANCE 1%
J 0
(65 2983);
DISPLAY 0.638298 (65 2983);
FORCEPROP 0 LAST ROOM NIC_P12V_MPS_MAM_BOM2
J 0
(50 2750);
DISPLAY 0.446809 (50 2750);
PAINT RED (50 2750);
FORCEPROP 2 LAST CDS_LIB pure_quanta
J 0
(20 2958);
DISPLAY INVISIBLE (20 2958);
FORCEPROP 1 LAST PATH I36
J 0
(70 3133);
DISPLAY 0.978723 (70 3133);
PAINT WHITE (70 3133);
DISPLAY INVISIBLE (70 3133);
FORCEPROP 1 LAST PART_NUMBER CS41202FB05
J 0
(60 2833);
DISPLAY 0.638298 (60 2833);
DISPLAY INVISIBLE (60 2833);
FORCEADD Q_RES..2
(550 2950);
FORCEPROP 1 LAST LOCATION PR3857
J 0
(600 3100);
DISPLAY 0.638298 (600 3100);
FORCEPROP 0 LAST $SEC 1
J 0
(605 3117);
DISPLAY 0.680851 (605 3117);
PAINT MONO (605 3117);
DISPLAY INVISIBLE (605 3117);
FORCEPROP 0 LAST CDS_SEC 1
J 0
(605 3117);
DISPLAY 1.021277 (605 3117);
DISPLAY INVISIBLE (605 3117);
FORCEPROP 1 LASTPIN (550 3050) $PN 1
J 0
(555 3012);
DISPLAY 0.787234 (555 3012);
PAINT MONO (555 3012);
FORCEPROP 1 LASTPIN (550 2850) $PN 2
J 0
(555 2860);
DISPLAY 0.787234 (555 2860);
PAINT MONO (555 2860);
FORCEPROP 1 LAST MATERIAL CHIP
J 0
(600 2900);
DISPLAY 0.638298 (600 2900);
PAINT RED (600 2900);
FORCEPROP 0 LAST ROOM NIC_P12V_MPS_MAM_BOM2
J 0
(600 2775);
DISPLAY 0.446809 (600 2775);
PAINT RED (600 2775);
FORCEPROP 1 LAST PACK_TYPE 0603LF
J 0
(600 2800);
DISPLAY 0.638298 (600 2800);
FORCEPROP 1 LAST WATTAGE 1/10W
J 0
(600 2950);
DISPLAY 0.638298 (600 2950);
FORCEPROP 1 LAST VALUE 49.9
J 0
(600 3050);
DISPLAY 0.638298 (600 3050);
FORCEPROP 1 LAST TOLERANCE 1%
J 0
(600 3000);
DISPLAY 0.638298 (600 3000);
FORCEPROP 2 LAST CDS_LIB pure_quanta
J 0
(550 2950);
DISPLAY INVISIBLE (550 2950);
FORCEPROP 1 LAST PATH I37
J 0
(600 3125);
DISPLAY 0.978723 (600 3125);
PAINT WHITE (600 3125);
DISPLAY INVISIBLE (600 3125);
FORCEPROP 1 LAST PART_NUMBER CS04993F909
J 0
(600 2850);
DISPLAY 0.638298 (600 2850);
DISPLAY INVISIBLE (600 2850);
FORCEADD UNIVERSAL_POWER..1
(500 3225);
FORCEPROP 3 LASTPIN (500 3175) SIG_NAME P12V_AUX\g
J 0
(510 3185);
DISPLAY 0.659574 (510 3185);
PAINT MONO (510 3185);
DISPLAY INVISIBLE (510 3185);
FORCEPROP 1 LAST HDL_POWER P12V_AUX
J 1
(500 3275);
DISPLAY 0.702128 (500 3275);
PAINT GREEN (500 3275);
FORCEPROP 2 LAST CDS_LIB pure_quanta_power
J 0
(500 3225);
DISPLAY INVISIBLE (500 3225);
FORCEPROP 1 LAST PATH I38
J 0
(550 3250);
DISPLAY 0.872340 (550 3250);
PAINT AQUA (550 3250);
DISPLAY INVISIBLE (550 3250);
FORCEADD GND..1
(1050 2950);
FORCEPROP 3 LASTPIN (1050 3000) SIG_NAME GND\g
J 0
(1060 3010);
DISPLAY 0.659574 (1060 3010);
PAINT MONO (1060 3010);
DISPLAY INVISIBLE (1060 3010);
FORCEPROP 2 LAST CDS_LIB pure_quanta_power
J 0
(1050 2950);
DISPLAY INVISIBLE (1050 2950);
FORCEPROP 1 LAST SIZE 1B
J 0
(1125 2900);
DISPLAY 0.872340 (1125 2900);
PAINT GREEN (1125 2900);
DISPLAY INVISIBLE (1125 2900);
FORCEPROP 1 LAST HDL_POWER GND
J 0
(1050 3100);
DISPLAY 0.872340 (1050 3100);
PAINT GREEN (1050 3100);
DISPLAY INVISIBLE (1050 3100);
FORCEPROP 1 LAST PATH I39
J 0
(1125 2950);
DISPLAY 0.872340 (1125 2950);
PAINT AQUA (1125 2950);
DISPLAY INVISIBLE (1125 2950);
FORCEADD Q_RES..2
(-3175 2450);
FORCEPROP 1 LAST LOCATION PR3847
J 0
(-3130 2575);
DISPLAY 0.638298 (-3130 2575);
FORCEPROP 0 LAST $SEC 1
J 0
(-3120 2617);
DISPLAY 0.680851 (-3120 2617);
PAINT MONO (-3120 2617);
DISPLAY INVISIBLE (-3120 2617);
FORCEPROP 0 LAST CDS_SEC 1
J 0
(-3125 2600);
DISPLAY INVISIBLE (-3125 2600);
FORCEPROP 1 LASTPIN (-3175 2550) $PN 1
J 0
(-3170 2512);
DISPLAY 0.787234 (-3170 2512);
PAINT MONO (-3170 2512);
FORCEPROP 1 LASTPIN (-3175 2350) $PN 2
J 0
(-3170 2360);
DISPLAY 0.787234 (-3170 2360);
PAINT MONO (-3170 2360);
FORCEPROP 1 LAST MATERIAL CHIP
J 0
(-3135 2375);
DISPLAY 0.638298 (-3135 2375);
PAINT RED (-3135 2375);
FORCEPROP 0 LAST ROOM NIC_P12V_MPS_MAM_BOM2
J 0
(-3250 2250);
DISPLAY 0.446809 (-3250 2250);
PAINT RED (-3250 2250);
FORCEPROP 1 LAST PACK_TYPE 0402LF
J 0
(-3135 2275);
DISPLAY 0.638298 (-3135 2275);
FORCEPROP 1 LAST VALUE 14.3K
J 0
(-3130 2525);
DISPLAY 0.638298 (-3130 2525);
FORCEPROP 1 LAST TOLERANCE 1%
J 0
(-3130 2475);
DISPLAY 0.638298 (-3130 2475);
FORCEPROP 1 LAST WATTAGE 1/16W
J 0
(-3135 2425);
DISPLAY 0.638298 (-3135 2425);
FORCEPROP 2 LAST CDS_LIB pure_quanta
J 0
(-3175 2450);
DISPLAY INVISIBLE (-3175 2450);
FORCEPROP 1 LAST PATH I4
J 0
(-3125 2625);
DISPLAY 0.978723 (-3125 2625);
PAINT WHITE (-3125 2625);
DISPLAY INVISIBLE (-3125 2625);
FORCEPROP 1 LAST PART_NUMBER CS31432FB02
J 0
(-3135 2325);
DISPLAY 0.638298 (-3135 2325);
DISPLAY INVISIBLE (-3135 2325);
FORCEADD Q_CAP..1
R 2
(1050 3200);
FORCEPROP 1 LAST LOCATION PC2174
J 0
(1100 3325);
DISPLAY 0.638298 (1100 3325);
FORCEPROP 0 LAST $SEC 1
J 0
(1100 3375);
DISPLAY 0.680851 (1100 3375);
PAINT MONO (1100 3375);
DISPLAY INVISIBLE (1100 3375);
FORCEPROP 0 LAST CDS_SEC 1
J 0
(1100 3375);
DISPLAY 1.021277 (1100 3375);
DISPLAY INVISIBLE (1100 3375);
FORCEPROP 1 LASTPIN (1050 3300) $PN 1
J 2
(1040 3280);
DISPLAY 0.787234 (1040 3280);
PAINT MONO (1040 3280);
FORCEPROP 1 LASTPIN (1050 3100) $PN 2
J 2
(1040 3080);
DISPLAY 0.787234 (1040 3080);
PAINT MONO (1040 3080);
FORCEPROP 0 LAST ROOM NIC_P12V_MPS_MAM_BOM2
J 0
(1100 3425);
DISPLAY 0.680851 (1100 3425);
PAINT RED (1100 3425);
FORCEPROP 1 LAST VOLTAGE 25V
J 0
(1100 3225);
DISPLAY 0.638298 (1100 3225);
FORCEPROP 1 LAST MATERIAL X7R
J 0
(1100 3125);
DISPLAY 0.638298 (1100 3125);
PAINT RED (1100 3125);
FORCEPROP 1 LAST PACK_TYPE 0402
J 0
(1100 3075);
DISPLAY 0.638298 (1100 3075);
FORCEPROP 1 LAST VALUE 0.1UF
J 0
(1100 3275);
DISPLAY 0.638298 (1100 3275);
FORCEPROP 1 LAST TOLERANCE 10%
J 0
(1100 3175);
DISPLAY 0.638298 (1100 3175);
FORCEPROP 2 LAST CDS_LIB pure_quanta
J 0
(1050 3200);
DISPLAY INVISIBLE (1050 3200);
FORCEPROP 1 LAST PATH I40
J 2
(1000 3350);
DISPLAY 0.978723 (1000 3350);
PAINT WHITE (1000 3350);
DISPLAY INVISIBLE (1000 3350);
FORCEPROP 1 LAST PART_NUMBER CH4104K1B00
J 0
(1100 3025);
DISPLAY 0.638298 (1100 3025);
DISPLAY INVISIBLE (1100 3025);
FORCEADD UNIVERSAL_POWER..1
R 2
(1050 3500);
FORCEPROP 3 LASTPIN (1050 3450) SIG_NAME P12V_OCP_V3_2\g
J 0
(1060 3460);
DISPLAY 0.659574 (1060 3460);
PAINT MONO (1060 3460);
DISPLAY INVISIBLE (1060 3460);
FORCEPROP 1 LAST HDL_POWER P12V_OCP_V3_2
J 1
(1075 3550);
DISPLAY 0.723404 (1075 3550);
PAINT GREEN (1075 3550);
FORCEPROP 2 LAST CDS_LIB pure_quanta_power
J 0
(1050 3500);
DISPLAY INVISIBLE (1050 3500);
FORCEPROP 1 LAST PATH I41
J 2
(1000 3525);
DISPLAY 0.872340 (1000 3525);
PAINT AQUA (1000 3525);
DISPLAY INVISIBLE (1000 3525);
FORCEADD OFFPAGE..2
(1475 2700);
PAINT AQUA (1475 2700);
FORCEPROP 2 LAST $XR0 141 
J 0
(1664 2700);
DISPLAY 0.638298 (1664 2700);
PAINT MONO (1664 2700);
FORCEPROP 2 LAST CDS_LIB standard
J 0
(1475 2700);
DISPLAY INVISIBLE (1475 2700);
FORCEPROP 1 LAST OFFPAGE TRUE
J 0
(1800 2575);
DISPLAY 0.872340 (1800 2575);
PAINT AQUA (1800 2575);
DISPLAY INVISIBLE (1800 2575);
FORCEPROP 1 LAST COMMENT_BODY TRUE
J 0
(1430 2605);
DISPLAY 0.872340 (1430 2605);
PAINT GREEN (1430 2605);
DISPLAY INVISIBLE (1430 2605);
FORCEPROP 2 LAST PATH I42
J 0
(1675 2750);
DISPLAY 1.021277 (1675 2750);
DISPLAY INVISIBLE (1675 2750);
FORCEADD Q_RES..2
(150 6175);
FORCEPROP 1 LAST LOCATION PR3855
J 0
(175 6250);
DISPLAY 0.723404 (175 6250);
PAINT AQUA (175 6250);
FORCEPROP 0 LAST $SEC 1
J 0
(175 6300);
DISPLAY INVISIBLE (175 6300);
FORCEPROP 0 LAST CDS_SEC 1
J 0
(175 6300);
DISPLAY INVISIBLE (175 6300);
FORCEPROP 1 LASTPIN (150 6275) $PN 1
J 0
(155 6237);
DISPLAY 0.787234 (155 6237);
PAINT MONO (155 6237);
DISPLAY INVISIBLE (155 6237);
FORCEPROP 1 LASTPIN (150 6075) $PN 2
J 0
(155 6085);
DISPLAY 0.787234 (155 6085);
PAINT MONO (155 6085);
DISPLAY INVISIBLE (155 6085);
FORCEPROP 0 LAST ROOM NIC_P3V3_BOM2
J 0
(150 5975);
DISPLAY 0.553191 (150 5975);
PAINT RED (150 5975);
FORCEPROP 1 LAST MATERIAL CHIP
J 0
(175 6050);
DISPLAY 0.723404 (175 6050);
PAINT RED (175 6050);
FORCEPROP 1 LAST VALUE 71.5K
J 0
(175 6200);
DISPLAY 0.574468 (175 6200);
PAINT SKYBLUE (175 6200);
FORCEPROP 1 LAST PACK_TYPE 0402LF
J 0
(175 6100);
DISPLAY 0.574468 (175 6100);
PAINT SKYBLUE (175 6100);
FORCEPROP 1 LAST TOLERANCE 1%
J 0
(175 6150);
DISPLAY 0.574468 (175 6150);
PAINT SKYBLUE (175 6150);
FORCEPROP 2 LAST CDS_LIB pure_quanta
J 0
(150 6175);
DISPLAY INVISIBLE (150 6175);
FORCEPROP 1 LAST WATTAGE 1/16W
J 0
(175 6150);
DISPLAY 0.723404 (175 6150);
PAINT SKYBLUE (175 6150);
DISPLAY INVISIBLE (175 6150);
FORCEPROP 1 LAST PATH I43
J 0
(200 6350);
DISPLAY 0.978723 (200 6350);
PAINT WHITE (200 6350);
DISPLAY INVISIBLE (200 6350);
FORCEPROP 1 LAST PART_NUMBER CS37152FB05
J 0
(155 6017);
DISPLAY 0.595745 (155 6017);
PAINT WHITE (155 6017);
DISPLAY INVISIBLE (155 6017);
FORCEADD UNIVERSAL_GND..1
(495 5883);
FORCEPROP 3 LASTPIN (495 5933) SIG_NAME GND\g
J 0
(505 5943);
DISPLAY 0.659574 (505 5943);
PAINT MONO (505 5943);
DISPLAY INVISIBLE (505 5943);
FORCEPROP 2 LAST CDS_LIB pure_quanta_power
J 0
(495 5883);
DISPLAY INVISIBLE (495 5883);
FORCEPROP 1 LAST HDL_POWER GND
J 1
(520 5808);
DISPLAY 0.872340 (520 5808);
PAINT GREEN (520 5808);
DISPLAY INVISIBLE (520 5808);
FORCEPROP 1 LAST PATH I45
J 0
(570 5883);
DISPLAY 0.872340 (570 5883);
PAINT AQUA (570 5883);
DISPLAY INVISIBLE (570 5883);
FORCEADD Q_RES..1
R 1
(495 6158);
FORCEPROP 1 LAST LOCATION PR3856
J 0
(525 6225);
DISPLAY 0.638298 (525 6225);
FORCEPROP 0 LAST $SEC 1
R 1
J 0
(520 6233);
DISPLAY INVISIBLE (520 6233);
FORCEPROP 0 LAST CDS_SEC 1
R 1
J 0
(520 6233);
DISPLAY INVISIBLE (520 6233);
FORCEPROP 1 LASTPIN (495 6058) $PN 1
R 1
J 0
(483 6070);
DISPLAY 0.787234 (483 6070);
PAINT MONO (483 6070);
DISPLAY INVISIBLE (483 6070);
FORCEPROP 1 LASTPIN (495 6258) $PN 2
R 1
J 0
(483 6220);
DISPLAY 0.787234 (483 6220);
PAINT MONO (483 6220);
DISPLAY INVISIBLE (483 6220);
FORCEPROP 1 LAST PACK_TYPE 0402LF
J 0
(525 6075);
DISPLAY 0.638298 (525 6075);
FORCEPROP 1 LAST MATERIAL CHIP
J 0
(525 5950);
DISPLAY 0.787234 (525 5950);
PAINT RED (525 5950);
FORCEPROP 0 LAST ROOM NIC_P3V3_BOM2
J 0
(525 5925);
DISPLAY 0.446809 (525 5925);
PAINT RED (525 5925);
FORCEPROP 1 LAST VALUE 1.33K
J 0
(525 6175);
DISPLAY 0.638298 (525 6175);
FORCEPROP 1 LAST TOLERANCE 1%
J 0
(525 6125);
DISPLAY 0.638298 (525 6125);
FORCEPROP 2 LAST CDS_LIB pure_quanta
J 0
(495 6158);
DISPLAY INVISIBLE (495 6158);
FORCEPROP 1 LAST WATTAGE 1/16W
R 1
J 2
(645 6133);
DISPLAY 0.978723 (645 6133);
DISPLAY INVISIBLE (645 6133);
FORCEPROP 1 LAST PATH I46
R 1
J 0
(345 6108);
DISPLAY 0.978723 (345 6108);
PAINT WHITE (345 6108);
DISPLAY INVISIBLE (345 6108);
FORCEPROP 1 LAST PART_NUMBER CS21332FB05
J 0
(525 6025);
DISPLAY 0.638298 (525 6025);
DISPLAY INVISIBLE (525 6025);
FORCEADD UNIVERSAL_GND..1
(750 6550);
FORCEPROP 3 LASTPIN (750 6600) SIG_NAME GND\g
J 0
(760 6610);
DISPLAY 0.659574 (760 6610);
PAINT MONO (760 6610);
DISPLAY INVISIBLE (760 6610);
FORCEPROP 2 LAST CDS_LIB pure_quanta_power
J 0
(750 6550);
DISPLAY INVISIBLE (750 6550);
FORCEPROP 1 LAST HDL_POWER GND
J 1
(775 6475);
DISPLAY 0.872340 (775 6475);
PAINT GREEN (775 6475);
DISPLAY INVISIBLE (775 6475);
FORCEPROP 1 LAST PATH I47
J 0
(825 6550);
DISPLAY 0.872340 (825 6550);
PAINT AQUA (825 6550);
DISPLAY INVISIBLE (825 6550);
FORCEADD Q_CAP..1
(750 6750);
FORCEPROP 1 LAST LOCATION PC2169
J 0
(800 6850);
DISPLAY 0.638298 (800 6850);
FORCEPROP 0 LAST $SEC 1
J 0
(800 6900);
DISPLAY INVISIBLE (800 6900);
FORCEPROP 0 LAST CDS_SEC 1
J 0
(800 6900);
DISPLAY INVISIBLE (800 6900);
FORCEPROP 1 LASTPIN (750 6850) $PN 1
J 0
(760 6830);
DISPLAY 0.787234 (760 6830);
PAINT MONO (760 6830);
DISPLAY INVISIBLE (760 6830);
FORCEPROP 1 LASTPIN (750 6650) $PN 2
J 0
(760 6630);
DISPLAY 0.787234 (760 6630);
PAINT MONO (760 6630);
DISPLAY INVISIBLE (760 6630);
FORCEPROP 1 LAST VALUE 1UF
J 0
(800 6800);
DISPLAY 0.638298 (800 6800);
FORCEPROP 0 LAST ROOM NIC_P3V3_BOM2
J 0
(800 6900);
DISPLAY 0.553191 (800 6900);
PAINT RED (800 6900);
FORCEPROP 1 LAST VOLTAGE 25V
J 0
(800 6750);
DISPLAY 0.638298 (800 6750);
FORCEPROP 1 LAST MATERIAL X6S
J 0
(800 6650);
DISPLAY 0.638298 (800 6650);
PAINT RED (800 6650);
FORCEPROP 1 LAST TOLERANCE 10%
J 0
(800 6700);
DISPLAY 0.638298 (800 6700);
FORCEPROP 1 LAST PACK_TYPE C0402
J 0
(800 6550);
DISPLAY 0.638298 (800 6550);
FORCEPROP 2 LAST CDS_LIB pure_quanta
J 0
(750 6750);
DISPLAY INVISIBLE (750 6750);
FORCEPROP 1 LAST PATH I48
J 0
(800 6900);
DISPLAY 0.978723 (800 6900);
PAINT WHITE (800 6900);
DISPLAY INVISIBLE (800 6900);
FORCEPROP 1 LAST PART_NUMBER CH5104KEB02
J 0
(800 6600);
DISPLAY 0.638298 (800 6600);
DISPLAY INVISIBLE (800 6600);
FORCEADD UNIVERSAL_GND..1
(870 5883);
FORCEPROP 3 LASTPIN (870 5933) SIG_NAME GND\g
J 0
(880 5943);
DISPLAY 0.659574 (880 5943);
PAINT MONO (880 5943);
DISPLAY INVISIBLE (880 5943);
FORCEPROP 2 LAST CDS_LIB pure_quanta_power
J 0
(870 5883);
DISPLAY INVISIBLE (870 5883);
FORCEPROP 1 LAST HDL_POWER GND
J 1
(895 5808);
DISPLAY 0.872340 (895 5808);
PAINT GREEN (895 5808);
DISPLAY INVISIBLE (895 5808);
FORCEPROP 1 LAST PATH I49
J 0
(945 5883);
DISPLAY 0.872340 (945 5883);
PAINT AQUA (945 5883);
DISPLAY INVISIBLE (945 5883);
FORCEADD GND..1
(-2755 2133);
FORCEPROP 3 LASTPIN (-2755 2183) SIG_NAME GND\g
J 0
(-2745 2193);
DISPLAY 0.659574 (-2745 2193);
PAINT MONO (-2745 2193);
DISPLAY INVISIBLE (-2745 2193);
FORCEPROP 1 LAST SIZE 1B
J 0
(-2680 2083);
DISPLAY 0.872340 (-2680 2083);
PAINT GREEN (-2680 2083);
DISPLAY INVISIBLE (-2680 2083);
FORCEPROP 2 LAST CDS_LIB pure_quanta_power
J 0
(-2755 2133);
DISPLAY INVISIBLE (-2755 2133);
FORCEPROP 1 LAST HDL_POWER GND
J 0
(-2755 2283);
DISPLAY 0.872340 (-2755 2283);
PAINT GREEN (-2755 2283);
DISPLAY INVISIBLE (-2755 2283);
FORCEPROP 1 LAST PATH I5
J 0
(-2680 2133);
DISPLAY 0.872340 (-2680 2133);
PAINT AQUA (-2680 2133);
DISPLAY INVISIBLE (-2680 2133);
FORCEADD Q_CAP..1
(870 6108);
FORCEPROP 1 LAST LOCATION PC1321
J 0
(920 6208);
DISPLAY 0.723404 (920 6208);
PAINT AQUA (920 6208);
FORCEPROP 0 LAST $SEC 1
J 0
(920 6258);
DISPLAY INVISIBLE (920 6258);
FORCEPROP 0 LAST CDS_SEC 1
J 0
(920 6258);
DISPLAY INVISIBLE (920 6258);
FORCEPROP 1 LASTPIN (870 6208) $PN 1
J 0
(880 6188);
DISPLAY 0.787234 (880 6188);
PAINT MONO (880 6188);
DISPLAY INVISIBLE (880 6188);
FORCEPROP 1 LASTPIN (870 6008) $PN 2
J 0
(880 5988);
DISPLAY 0.787234 (880 5988);
PAINT MONO (880 5988);
DISPLAY INVISIBLE (880 5988);
FORCEPROP 1 LAST VALUE 0.068UF
J 0
(920 6183);
DISPLAY 0.574468 (920 6183);
PAINT SKYBLUE (920 6183);
FORCEPROP 1 LAST VOLTAGE 16V
J 0
(920 6083);
DISPLAY 0.574468 (920 6083);
PAINT SKYBLUE (920 6083);
FORCEPROP 0 LAST ROOM NIC_P3V3_BOM2
J 0
(925 5925);
DISPLAY 0.680851 (925 5925);
PAINT RED (925 5925);
FORCEPROP 1 LAST MATERIAL X7R
J 0
(920 6133);
DISPLAY 0.574468 (920 6133);
PAINT RED (920 6133);
FORCEPROP 1 LAST PACK_TYPE 0402
J 0
(920 6033);
DISPLAY 0.574468 (920 6033);
PAINT SKYBLUE (920 6033);
FORCEPROP 1 LAST TOLERANCE 10%
J 0
(920 6058);
DISPLAY 0.723404 (920 6058);
PAINT SKYBLUE (920 6058);
DISPLAY INVISIBLE (920 6058);
FORCEPROP 2 LAST CDS_LIB pure_quanta
J 0
(870 6108);
DISPLAY INVISIBLE (870 6108);
FORCEPROP 1 LAST PATH I50
J 0
(920 6258);
DISPLAY 0.978723 (920 6258);
PAINT WHITE (920 6258);
DISPLAY INVISIBLE (920 6258);
FORCEPROP 1 LAST PART_NUMBER CH3683K1B09
J 0
(920 5983);
DISPLAY 0.574468 (920 5983);
PAINT WHITE (920 5983);
DISPLAY INVISIBLE (920 5983);
FORCEADD MP5016GQHLZ..1
(1675 6425);
FORCEPROP 1 LAST LOCATION PU207
J 0
(1430 6906);
DISPLAY 0.723404 (1430 6906);
PAINT GREEN (1430 6906);
FORCEPROP 0 LAST $SEC 1
J 0
(1450 7050);
DISPLAY INVISIBLE (1450 7050);
FORCEPROP 0 LAST CDS_SEC 1
J 0
(1450 7050);
DISPLAY INVISIBLE (1450 7050);
FORCEPROP 0 LASTPIN (1275 6275) $PN 10
J 2
(1265 6285);
DISPLAY 0.808511 (1265 6285);
FORCEPROP 0 LASTPIN (1275 6475) $PN 9
J 2
(1265 6485);
DISPLAY 0.808511 (1265 6485);
FORCEPROP 0 LASTPIN (2075 6375) $PN 8
J 0
(2085 6385);
DISPLAY 0.808511 (2085 6385);
FORCEPROP 0 LASTPIN (2075 6275) $PN 3
J 0
(2085 6285);
DISPLAY 0.808511 (2085 6285);
FORCEPROP 0 LASTPIN (1275 6325) $PN 4
J 2
(1265 6335);
DISPLAY 0.808511 (1265 6335);
FORCEPROP 0 LASTPIN (1275 6375) $PN 5
J 2
(1265 6385);
DISPLAY 0.808511 (1265 6385);
FORCEPROP 0 LASTPIN (2075 6575) $PN 6_7
J 0
(2085 6585);
DISPLAY 0.808511 (2085 6585);
FORCEPROP 0 LASTPIN (1275 6575) $PN 1_2
J 2
(1265 6585);
DISPLAY 0.808511 (1265 6585);
FORCEPROP 2 LAST VALUE MP5016GQH-L-Z
J 0
(1450 6950);
DISPLAY 0.680851 (1450 6950);
FORCEPROP 0 LAST ROOM NIC_P3V3_BOM2
J 0
(1450 7100);
DISPLAY 0.680851 (1450 7100);
PAINT RED (1450 7100);
FORCEPROP 2 LAST PART_TYPE SMLF
J 0
(1450 7000);
DISPLAY 0.680851 (1450 7000);
FORCEPROP 1 LAST MATERIAL IC
J 0
(1430 6632);
DISPLAY 0.723404 (1430 6632);
PAINT RED (1430 6632);
FORCEPROP 2 LAST CDS_LIB pure_quanta
J 0
(1675 6425);
DISPLAY INVISIBLE (1675 6425);
FORCEPROP 1 LAST CDS_LMAN_SYM_OUTLINE -250,200,250,-200
J 0
(1675 6425);
DISPLAY 0.468085 (1675 6425);
PAINT GREEN (1675 6425);
DISPLAY INVISIBLE (1675 6425);
FORCEPROP 1 LAST NEEDS_NO_SIZE TRUE
J 0
(1675 6425);
DISPLAY 0.723404 (1675 6425);
PAINT GREEN (1675 6425);
DISPLAY INVISIBLE (1675 6425);
FORCEPROP 1 LAST PATH I51
J 0
(1675 6425);
DISPLAY 0.723404 (1675 6425);
PAINT GREEN (1675 6425);
DISPLAY INVISIBLE (1675 6425);
FORCEPROP 1 LAST PART_NUMBER AL005016007
J 0
(1430 6759);
DISPLAY 0.723404 (1430 6759);
PAINT GREEN (1430 6759);
DISPLAY INVISIBLE (1430 6759);
FORCEADD UNIVERSAL_POWER..1
R 2
(825 7125);
FORCEPROP 3 LASTPIN (825 7075) SIG_NAME P3V3_AUX\g
J 0
(835 7085);
DISPLAY 0.659574 (835 7085);
PAINT MONO (835 7085);
DISPLAY INVISIBLE (835 7085);
FORCEPROP 1 LAST HDL_POWER P3V3_AUX
J 1
(825 7175);
DISPLAY 0.723404 (825 7175);
PAINT GREEN (825 7175);
FORCEPROP 2 LAST CDS_LIB pure_quanta_power
J 0
(825 7125);
DISPLAY INVISIBLE (825 7125);
FORCEPROP 1 LAST PATH I52
J 2
(775 7150);
DISPLAY 0.872340 (775 7150);
PAINT AQUA (775 7150);
DISPLAY INVISIBLE (775 7150);
FORCEADD UNIVERSAL_GND..1
(2500 5800);
FORCEPROP 3 LASTPIN (2500 5850) SIG_NAME GND\g
J 0
(2510 5860);
DISPLAY 0.659574 (2510 5860);
PAINT MONO (2510 5860);
DISPLAY INVISIBLE (2510 5860);
FORCEPROP 2 LAST CDS_LIB pure_quanta_power
J 0
(2500 5800);
DISPLAY INVISIBLE (2500 5800);
FORCEPROP 1 LAST HDL_POWER GND
J 1
(2525 5725);
DISPLAY 0.872340 (2525 5725);
PAINT GREEN (2525 5725);
DISPLAY INVISIBLE (2525 5725);
FORCEPROP 1 LAST PATH I53
J 0
(2575 5800);
DISPLAY 0.872340 (2575 5800);
PAINT AQUA (2575 5800);
DISPLAY INVISIBLE (2575 5800);
FORCEADD Q_CAP..1
(2500 6150);
FORCEPROP 1 LAST LOCATION PC1322
J 0
(2550 6225);
DISPLAY 0.723404 (2550 6225);
PAINT AQUA (2550 6225);
FORCEPROP 0 LAST $SEC 1
J 0
(2550 6275);
DISPLAY INVISIBLE (2550 6275);
FORCEPROP 0 LAST CDS_SEC 1
J 0
(2550 6275);
DISPLAY INVISIBLE (2550 6275);
FORCEPROP 1 LASTPIN (2500 6250) $PN 1
J 0
(2510 6230);
DISPLAY 0.787234 (2510 6230);
PAINT MONO (2510 6230);
DISPLAY INVISIBLE (2510 6230);
FORCEPROP 1 LASTPIN (2500 6050) $PN 2
J 0
(2510 6030);
DISPLAY 0.787234 (2510 6030);
PAINT MONO (2510 6030);
DISPLAY INVISIBLE (2510 6030);
FORCEPROP 0 LAST ROOM NIC_P3V3_BOM2
J 0
(2550 5925);
DISPLAY 0.553191 (2550 5925);
PAINT RED (2550 5925);
FORCEPROP 1 LAST MATERIAL X7R
J 0
(2550 6125);
DISPLAY 0.574468 (2550 6125);
PAINT RED (2550 6125);
FORCEPROP 1 LAST PACK_TYPE 0402
J 0
(2550 6025);
DISPLAY 0.574468 (2550 6025);
PAINT SKYBLUE (2550 6025);
FORCEPROP 1 LAST VOLTAGE 50V
J 0
(2550 6075);
DISPLAY 0.574468 (2550 6075);
PAINT SKYBLUE (2550 6075);
FORCEPROP 1 LAST VALUE 100PF
J 0
(2550 6175);
DISPLAY 0.574468 (2550 6175);
PAINT SKYBLUE (2550 6175);
FORCEPROP 1 LAST TOLERANCE 5%
J 0
(2550 6100);
DISPLAY 0.723404 (2550 6100);
PAINT SKYBLUE (2550 6100);
DISPLAY INVISIBLE (2550 6100);
FORCEPROP 2 LAST CDS_LIB pure_quanta
J 0
(2500 6150);
DISPLAY INVISIBLE (2500 6150);
FORCEPROP 1 LAST PATH I54
J 0
(2550 6300);
DISPLAY 0.978723 (2550 6300);
PAINT WHITE (2550 6300);
DISPLAY INVISIBLE (2550 6300);
FORCEPROP 1 LAST PART_NUMBER CH11006JB18
J 0
(2550 5975);
DISPLAY 0.574468 (2550 5975);
PAINT WHITE (2550 5975);
DISPLAY INVISIBLE (2550 5975);
FORCEADD UNIVERSAL_GND..1
(2900 6000);
FORCEPROP 3 LASTPIN (2900 6050) SIG_NAME GND\g
J 0
(2910 6060);
DISPLAY 0.659574 (2910 6060);
PAINT MONO (2910 6060);
DISPLAY INVISIBLE (2910 6060);
FORCEPROP 2 LAST CDS_LIB pure_quanta_power
J 0
(2900 6000);
DISPLAY INVISIBLE (2900 6000);
FORCEPROP 1 LAST HDL_POWER GND
J 1
(2925 5925);
DISPLAY 0.872340 (2925 5925);
PAINT GREEN (2925 5925);
DISPLAY INVISIBLE (2925 5925);
FORCEPROP 1 LAST PATH I55
J 0
(2975 6000);
DISPLAY 0.872340 (2975 6000);
PAINT AQUA (2975 6000);
DISPLAY INVISIBLE (2975 6000);
FORCEADD Q_CAP..1
(2900 6350);
FORCEPROP 1 LAST LOCATION PC2173
J 0
(2950 6450);
DISPLAY 0.787234 (2950 6450);
FORCEPROP 0 LAST $SEC 1
J 0
(2950 6500);
DISPLAY INVISIBLE (2950 6500);
FORCEPROP 0 LAST CDS_SEC 1
J 0
(2950 6500);
DISPLAY INVISIBLE (2950 6500);
FORCEPROP 1 LASTPIN (2900 6450) $PN 1
J 0
(2910 6430);
DISPLAY 0.787234 (2910 6430);
PAINT MONO (2910 6430);
DISPLAY INVISIBLE (2910 6430);
FORCEPROP 1 LASTPIN (2900 6250) $PN 2
J 0
(2910 6230);
DISPLAY 0.787234 (2910 6230);
PAINT MONO (2910 6230);
DISPLAY INVISIBLE (2910 6230);
FORCEPROP 1 LAST VALUE 10UF
J 0
(2950 6400);
DISPLAY 0.787234 (2950 6400);
FORCEPROP 1 LAST VOLTAGE 16V
J 0
(2950 6350);
DISPLAY 0.787234 (2950 6350);
FORCEPROP 1 LAST TOLERANCE 10%
J 0
(2950 6300);
DISPLAY 0.787234 (2950 6300);
FORCEPROP 0 LAST ROOM NIC_P3V3_BOM2
J 0
(2950 6550);
DISPLAY 0.680851 (2950 6550);
PAINT RED (2950 6550);
FORCEPROP 1 LAST MATERIAL X6S
J 0
(2950 6250);
DISPLAY 0.787234 (2950 6250);
PAINT RED (2950 6250);
FORCEPROP 1 LAST PACK_TYPE C0805
J 0
(2950 6150);
DISPLAY 0.787234 (2950 6150);
FORCEPROP 2 LAST CDS_LIB pure_quanta
J 0
(2900 6350);
DISPLAY INVISIBLE (2900 6350);
FORCEPROP 1 LAST PATH I56
J 0
(2950 6500);
DISPLAY 0.978723 (2950 6500);
PAINT WHITE (2950 6500);
DISPLAY INVISIBLE (2950 6500);
FORCEPROP 1 LAST PART_NUMBER CH6103KEA01
J 0
(2950 6200);
DISPLAY 0.787234 (2950 6200);
DISPLAY INVISIBLE (2950 6200);
FORCEADD UNIVERSAL_POWER..1
R 2
(2900 6900);
FORCEPROP 3 LASTPIN (2900 6850) SIG_NAME P3V3_OCP_V3_2_R\g
J 0
(2910 6860);
DISPLAY 0.659574 (2910 6860);
PAINT MONO (2910 6860);
DISPLAY INVISIBLE (2910 6860);
FORCEPROP 1 LAST HDL_POWER P3V3_OCP_V3_2_R
J 1
(2900 6950);
DISPLAY 0.723404 (2900 6950);
PAINT GREEN (2900 6950);
FORCEPROP 2 LAST CDS_LIB pure_quanta_power
J 0
(2900 6900);
DISPLAY INVISIBLE (2900 6900);
FORCEPROP 1 LAST PATH I57
J 2
(2850 6925);
DISPLAY 0.872340 (2850 6925);
PAINT AQUA (2850 6925);
DISPLAY INVISIBLE (2850 6925);
FORCEADD Q_CAP..1
(-975 2200);
FORCEPROP 1 LAST LOCATION PC2167
J 0
(-925 2300);
DISPLAY 0.808511 (-925 2300);
FORCEPROP 0 LAST $SEC 1
J 0
(-925 2350);
DISPLAY 0.680851 (-925 2350);
PAINT MONO (-925 2350);
DISPLAY INVISIBLE (-925 2350);
FORCEPROP 0 LAST CDS_SEC 1
J 0
(-925 2350);
DISPLAY 0.680851 (-925 2350);
DISPLAY INVISIBLE (-925 2350);
FORCEPROP 1 LASTPIN (-975 2300) $PN 1
J 0
(-965 2280);
DISPLAY 0.787234 (-965 2280);
PAINT MONO (-965 2280);
FORCEPROP 1 LASTPIN (-975 2100) $PN 2
J 0
(-965 2080);
DISPLAY 0.787234 (-965 2080);
PAINT MONO (-965 2080);
FORCEPROP 1 LAST VALUE 100PF
J 0
(-925 2250);
DISPLAY 0.638298 (-925 2250);
FORCEPROP 0 LAST ROOM NIC_P12V_MPS_MAM_BOM2
J 0
(-925 1975);
DISPLAY 0.446809 (-925 1975);
PAINT RED (-925 1975);
FORCEPROP 1 LAST VOLTAGE 50V
J 0
(-925 2200);
DISPLAY 0.638298 (-925 2200);
FORCEPROP 1 LAST TOLERANCE 5%
J 0
(-925 2150);
DISPLAY 0.638298 (-925 2150);
FORCEPROP 1 LAST MATERIAL NPO
J 0
(-925 2100);
DISPLAY 0.638298 (-925 2100);
PAINT RED (-925 2100);
FORCEPROP 1 LAST PACK_TYPE 0402
J 0
(-925 2000);
DISPLAY 0.638298 (-925 2000);
FORCEPROP 2 LAST CDS_LIB pure_quanta
J 0
(-975 2200);
DISPLAY INVISIBLE (-975 2200);
FORCEPROP 1 LAST PATH I58
J 0
(-925 2350);
DISPLAY 0.978723 (-925 2350);
PAINT WHITE (-925 2350);
DISPLAY INVISIBLE (-925 2350);
FORCEPROP 1 LAST PART_NUMBER CH11006JB00
J 0
(-925 2050);
DISPLAY 0.638298 (-925 2050);
DISPLAY INVISIBLE (-925 2050);
FORCEADD Q_CAP..1
(-2755 2383);
FORCEPROP 1 LAST LOCATION PC2166
J 0
(-2705 2483);
DISPLAY 0.787234 (-2705 2483);
FORCEPROP 0 LAST $SEC 1
J 0
(-2705 2533);
DISPLAY INVISIBLE (-2705 2533);
FORCEPROP 0 LAST CDS_SEC 1
J 0
(-2705 2533);
DISPLAY INVISIBLE (-2705 2533);
FORCEPROP 1 LASTPIN (-2755 2483) $PN 1
J 0
(-2745 2463);
DISPLAY 0.787234 (-2745 2463);
PAINT MONO (-2745 2463);
DISPLAY INVISIBLE (-2745 2463);
FORCEPROP 1 LASTPIN (-2755 2283) $PN 2
J 0
(-2745 2263);
DISPLAY 0.787234 (-2745 2263);
PAINT MONO (-2745 2263);
DISPLAY INVISIBLE (-2745 2263);
FORCEPROP 0 LAST ROOM NIC_P12V_MPS_MAM_BOM2
J 0
(-2700 2200);
DISPLAY 0.446809 (-2700 2200);
PAINT RED (-2700 2200);
FORCEPROP 1 LAST MATERIAL X7R
J 0
(-2713 2382);
DISPLAY 0.638298 (-2713 2382);
PAINT RED (-2713 2382);
FORCEPROP 1 LAST VALUE 0.047UF
J 0
(-2705 2433);
DISPLAY 0.638298 (-2705 2433);
FORCEPROP 1 LAST PACK_TYPE C0402
J 0
(-2713 2282);
DISPLAY 0.638298 (-2713 2282);
FORCEPROP 1 LAST VOLTAGE 25V
J 0
(-2713 2332);
DISPLAY 0.638298 (-2713 2332);
FORCEPROP 1 LAST TOLERANCE 10%
J 0
(-2705 2333);
DISPLAY 0.638298 (-2705 2333);
DISPLAY INVISIBLE (-2705 2333);
FORCEPROP 2 LAST CDS_LIB pure_quanta
J 0
(-2755 2383);
DISPLAY INVISIBLE (-2755 2383);
FORCEPROP 1 LAST PATH I6
J 0
(-2705 2533);
DISPLAY 0.978723 (-2705 2533);
PAINT WHITE (-2705 2533);
DISPLAY INVISIBLE (-2705 2533);
FORCEPROP 1 LAST PART_NUMBER CH3474K1B04
J 0
(-2713 2232);
DISPLAY 0.638298 (-2713 2232);
DISPLAY INVISIBLE (-2713 2232);
FORCEADD GND..1
(-2434 2316);
FORCEPROP 3 LASTPIN (-2434 2366) SIG_NAME GND\g
J 0
(-2424 2376);
DISPLAY 0.659574 (-2424 2376);
PAINT MONO (-2424 2376);
DISPLAY INVISIBLE (-2424 2376);
FORCEPROP 2 LAST CDS_LIB pure_quanta_power
J 0
(-2434 2316);
DISPLAY INVISIBLE (-2434 2316);
FORCEPROP 1 LAST SIZE 1B
J 0
(-2359 2266);
DISPLAY 0.872340 (-2359 2266);
PAINT GREEN (-2359 2266);
DISPLAY INVISIBLE (-2359 2266);
FORCEPROP 1 LAST HDL_POWER GND
J 0
(-2434 2466);
DISPLAY 0.872340 (-2434 2466);
PAINT GREEN (-2434 2466);
DISPLAY INVISIBLE (-2434 2466);
FORCEPROP 1 LAST PATH I7
J 0
(-2359 2316);
DISPLAY 0.872340 (-2359 2316);
PAINT AQUA (-2359 2316);
DISPLAY INVISIBLE (-2359 2316);
FORCEADD Q_RES..1
(-3500 3050);
FORCEPROP 1 LAST LOCATION R3630
J 0
(-3550 3075);
DISPLAY 0.638298 (-3550 3075);
FORCEPROP 0 LAST $SEC 1
J 0
(-3550 3125);
DISPLAY 0.680851 (-3550 3125);
PAINT MONO (-3550 3125);
DISPLAY INVISIBLE (-3550 3125);
FORCEPROP 0 LAST CDS_SEC 1
J 0
(-3550 3125);
DISPLAY 0.680851 (-3550 3125);
DISPLAY INVISIBLE (-3550 3125);
FORCEPROP 1 LASTPIN (-3600 3050) $PN 1
J 0
(-3588 3062);
DISPLAY 0.787234 (-3588 3062);
PAINT MONO (-3588 3062);
FORCEPROP 1 LASTPIN (-3400 3050) $PN 2
J 0
(-3438 3062);
DISPLAY 0.787234 (-3438 3062);
PAINT MONO (-3438 3062);
FORCEPROP 0 LAST ROOM NIC_P12V_MPS_MAM_BOM2
J 0
(-3725 3125);
DISPLAY 0.553191 (-3725 3125);
PAINT RED (-3725 3125);
FORCEPROP 1 LAST TOLERANCE 5%
J 0
(-3325 3050);
DISPLAY 0.510638 (-3325 3050);
FORCEPROP 1 LAST VALUE 0
J 2
(-3350 3050);
DISPLAY 0.510638 (-3350 3050);
FORCEPROP 1 LAST MATERIAL EMPTY
J 0
(-3550 3000);
DISPLAY 0.510638 (-3550 3000);
PAINT RED (-3550 3000);
FORCEPROP 2 LAST CDS_LIB pure_quanta
J 0
(-3500 3050);
DISPLAY INVISIBLE (-3500 3050);
FORCEPROP 1 LAST PACK_TYPE 0402LF
J 0
(-3250 3050);
DISPLAY 0.510638 (-3250 3050);
DISPLAY INVISIBLE (-3250 3050);
FORCEPROP 1 LAST WATTAGE 1/16W
J 2
(-3400 2975);
DISPLAY 0.319149 (-3400 2975);
DISPLAY INVISIBLE (-3400 2975);
FORCEPROP 1 LAST PATH I73
J 0
(-3550 3200);
DISPLAY 0.978723 (-3550 3200);
PAINT WHITE (-3550 3200);
DISPLAY INVISIBLE (-3550 3200);
FORCEPROP 1 LAST PART_NUMBER CS00002JB13
J 0
(-3575 3000);
DISPLAY 0.319149 (-3575 3000);
DISPLAY INVISIBLE (-3575 3000);
FORCEADD Q_RES..1
(225 6475);
FORCEPROP 1 LAST LOCATION R3631
J 0
(175 6500);
DISPLAY 0.638298 (175 6500);
FORCEPROP 0 LAST $SEC 1
J 0
(175 6550);
DISPLAY 0.680851 (175 6550);
PAINT MONO (175 6550);
DISPLAY INVISIBLE (175 6550);
FORCEPROP 0 LAST CDS_SEC 1
J 0
(175 6550);
DISPLAY 0.680851 (175 6550);
DISPLAY INVISIBLE (175 6550);
FORCEPROP 1 LASTPIN (125 6475) $PN 1
J 0
(137 6487);
DISPLAY 0.787234 (137 6487);
PAINT MONO (137 6487);
FORCEPROP 1 LASTPIN (325 6475) $PN 2
J 0
(287 6487);
DISPLAY 0.787234 (287 6487);
PAINT MONO (287 6487);
FORCEPROP 0 LAST ROOM NIC_P3V3_BOM2
J 0
(50 6600);
DISPLAY 0.680851 (50 6600);
PAINT RED (50 6600);
FORCEPROP 1 LAST TOLERANCE 5%
J 0
(400 6475);
DISPLAY 0.510638 (400 6475);
FORCEPROP 1 LAST VALUE 0
J 2
(375 6475);
DISPLAY 0.510638 (375 6475);
FORCEPROP 1 LAST MATERIAL EMPTY
J 0
(175 6425);
DISPLAY 0.510638 (175 6425);
PAINT RED (175 6425);
FORCEPROP 1 LAST WATTAGE 1/16W
J 2
(325 6400);
DISPLAY 0.319149 (325 6400);
DISPLAY INVISIBLE (325 6400);
FORCEPROP 1 LAST PACK_TYPE 0402LF
J 0
(475 6475);
DISPLAY 0.510638 (475 6475);
DISPLAY INVISIBLE (475 6475);
FORCEPROP 2 LAST CDS_LIB pure_quanta
J 0
(225 6475);
DISPLAY INVISIBLE (225 6475);
FORCEPROP 1 LAST PATH I74
J 0
(175 6625);
DISPLAY 0.978723 (175 6625);
PAINT WHITE (175 6625);
DISPLAY INVISIBLE (175 6625);
FORCEPROP 1 LAST PART_NUMBER CS00002JB13
J 0
(150 6425);
DISPLAY 0.319149 (150 6425);
DISPLAY INVISIBLE (150 6425);
FORCEADD OFFPAGE..1
(-4500 3500);
PAINT AQUA (-4500 3500);
FORCEPROP 2 LAST $XR3 248 
J 0
(-5112 3500);
DISPLAY 0.638298 (-5112 3500);
PAINT MONO (-5112 3500);
FORCEPROP 2 LAST $XR2 141 
J 0
(-4992 3500);
DISPLAY 0.638298 (-4992 3500);
PAINT MONO (-4992 3500);
FORCEPROP 2 LAST $XR1 140 
J 0
(-4872 3500);
DISPLAY 0.638298 (-4872 3500);
PAINT MONO (-4872 3500);
FORCEPROP 2 LAST $XR0 142 
J 0
(-4752 3500);
DISPLAY 0.638298 (-4752 3500);
PAINT MONO (-4752 3500);
FORCEPROP 2 LAST CDS_LIB standard
J 0
(-4500 3500);
DISPLAY INVISIBLE (-4500 3500);
FORCEPROP 1 LAST OFFPAGE TRUE
J 0
(-4175 3375);
DISPLAY 0.872340 (-4175 3375);
PAINT AQUA (-4175 3375);
DISPLAY INVISIBLE (-4175 3375);
FORCEPROP 1 LAST COMMENT_BODY TRUE
J 0
(-4375 3400);
DISPLAY 0.872340 (-4375 3400);
PAINT GREEN (-4375 3400);
DISPLAY INVISIBLE (-4375 3400);
FORCEPROP 2 LAST PATH I75
J 0
(-4450 3575);
DISPLAY 0.680851 (-4450 3575);
DISPLAY INVISIBLE (-4450 3575);
FORCEADD Q_RES..1
(-3450 3500);
FORCEPROP 1 LAST LOCATION R1193
J 0
(-3550 3550);
DISPLAY 0.787234 (-3550 3550);
FORCEPROP 0 LAST $SEC 1
J 0
(-3600 3550);
DISPLAY 0.680851 (-3600 3550);
PAINT MONO (-3600 3550);
DISPLAY INVISIBLE (-3600 3550);
FORCEPROP 0 LAST CDS_SEC 1
J 0
(-3600 3550);
DISPLAY 0.680851 (-3600 3550);
DISPLAY INVISIBLE (-3600 3550);
FORCEPROP 1 LASTPIN (-3550 3500) $PN 1
J 0
(-3538 3512);
DISPLAY 0.787234 (-3538 3512);
PAINT MONO (-3538 3512);
FORCEPROP 1 LASTPIN (-3350 3500) $PN 2
J 0
(-3388 3512);
DISPLAY 0.787234 (-3388 3512);
PAINT MONO (-3388 3512);
FORCEPROP 0 LAST ROOM NIC_P12V_MPS_MAM_BOM2
J 0
(-3575 3600);
DISPLAY 0.553191 (-3575 3600);
PAINT RED (-3575 3600);
FORCEPROP 1 LAST MATERIAL CHIP
J 0
(-3225 3500);
DISPLAY 0.510638 (-3225 3500);
FORCEPROP 1 LAST VALUE 0
J 2
(-3300 3500);
DISPLAY 0.510638 (-3300 3500);
FORCEPROP 1 LAST TOLERANCE 5%
J 0
(-3275 3500);
DISPLAY 0.510638 (-3275 3500);
FORCEPROP 1 LAST PACK_TYPE 0402LF
J 0
(-3200 3500);
DISPLAY 0.510638 (-3200 3500);
DISPLAY INVISIBLE (-3200 3500);
FORCEPROP 1 LAST WATTAGE 1/16W
J 2
(-3350 3425);
DISPLAY 0.319149 (-3350 3425);
DISPLAY INVISIBLE (-3350 3425);
FORCEPROP 2 LAST CDS_LIB pure_quanta
J 0
(-3450 3500);
DISPLAY INVISIBLE (-3450 3500);
FORCEPROP 1 LAST PATH I76
J 0
(-3500 3650);
DISPLAY 0.978723 (-3500 3650);
PAINT WHITE (-3500 3650);
DISPLAY INVISIBLE (-3500 3650);
FORCEPROP 1 LAST PART_NUMBER CS00002JB13
J 0
(-3525 3450);
DISPLAY 0.319149 (-3525 3450);
DISPLAY INVISIBLE (-3525 3450);
FORCEADD OFFPAGE..1
(-1150 6850);
PAINT AQUA (-1150 6850);
FORCEPROP 2 LAST $XR3 248 
J 0
(-1762 6850);
DISPLAY 0.638298 (-1762 6850);
PAINT MONO (-1762 6850);
FORCEPROP 2 LAST $XR2 142 
J 0
(-1642 6850);
DISPLAY 0.638298 (-1642 6850);
PAINT MONO (-1642 6850);
FORCEPROP 2 LAST $XR1 141 
J 0
(-1522 6850);
DISPLAY 0.638298 (-1522 6850);
PAINT MONO (-1522 6850);
FORCEPROP 2 LAST $XR0 140 
J 0
(-1402 6850);
DISPLAY 0.638298 (-1402 6850);
PAINT MONO (-1402 6850);
FORCEPROP 2 LAST CDS_LIB standard
J 0
(-1150 6850);
DISPLAY INVISIBLE (-1150 6850);
FORCEPROP 1 LAST OFFPAGE TRUE
J 0
(-825 6725);
DISPLAY 0.872340 (-825 6725);
PAINT AQUA (-825 6725);
DISPLAY INVISIBLE (-825 6725);
FORCEPROP 1 LAST COMMENT_BODY TRUE
J 0
(-1025 6750);
DISPLAY 0.872340 (-1025 6750);
PAINT GREEN (-1025 6750);
DISPLAY INVISIBLE (-1025 6750);
FORCEPROP 2 LAST PATH I77
J 0
(-1100 6925);
DISPLAY 0.680851 (-1100 6925);
DISPLAY INVISIBLE (-1100 6925);
FORCEADD Q_RES..1
(225 6850);
FORCEPROP 1 LAST LOCATION R1196
J 0
(175 6875);
DISPLAY 0.638298 (175 6875);
FORCEPROP 0 LAST $SEC 1
J 0
(50 7025);
DISPLAY 0.680851 (50 7025);
PAINT MONO (50 7025);
DISPLAY INVISIBLE (50 7025);
FORCEPROP 0 LAST CDS_SEC 1
J 0
(50 7025);
DISPLAY 0.680851 (50 7025);
DISPLAY INVISIBLE (50 7025);
FORCEPROP 1 LASTPIN (125 6850) $PN 1
J 0
(137 6862);
DISPLAY 0.787234 (137 6862);
PAINT MONO (137 6862);
FORCEPROP 1 LASTPIN (325 6850) $PN 2
J 0
(287 6862);
DISPLAY 0.787234 (287 6862);
PAINT MONO (287 6862);
FORCEPROP 1 LAST MATERIAL EMPTY
J 0
(175 6800);
DISPLAY 0.510638 (175 6800);
PAINT RED (175 6800);
FORCEPROP 1 LAST TOLERANCE 5%
J 0
(400 6850);
DISPLAY 0.510638 (400 6850);
FORCEPROP 1 LAST VALUE 0
J 2
(375 6850);
DISPLAY 0.510638 (375 6850);
FORCEPROP 0 LAST ROOM NIC_P3V3_BOM2
J 0
(50 6975);
DISPLAY 0.680851 (50 6975);
PAINT RED (50 6975);
FORCEPROP 2 LAST CDS_LIB pure_quanta
J 0
(225 6850);
DISPLAY INVISIBLE (225 6850);
FORCEPROP 1 LAST WATTAGE 1/16W
J 2
(325 6775);
DISPLAY 0.319149 (325 6775);
DISPLAY INVISIBLE (325 6775);
FORCEPROP 1 LAST PACK_TYPE 0402LF
J 0
(475 6850);
DISPLAY 0.510638 (475 6850);
DISPLAY INVISIBLE (475 6850);
FORCEPROP 1 LAST PATH I79
J 0
(175 7000);
DISPLAY 0.978723 (175 7000);
PAINT WHITE (175 7000);
DISPLAY INVISIBLE (175 7000);
FORCEPROP 1 LAST PART_NUMBER CS00002JB13
J 0
(150 6800);
DISPLAY 0.319149 (150 6800);
DISPLAY INVISIBLE (150 6800);
FORCEADD Q_RES..1
(125 7275);
FORCEPROP 1 LAST LOCATION R1521
J 0
(75 7325);
DISPLAY 0.978723 (75 7325);
FORCEPROP 0 LAST $SEC 1
J 0
(-25 7450);
DISPLAY 0.680851 (-25 7450);
PAINT MONO (-25 7450);
DISPLAY INVISIBLE (-25 7450);
FORCEPROP 0 LAST CDS_SEC 1
J 0
(-25 7450);
DISPLAY 0.680851 (-25 7450);
DISPLAY INVISIBLE (-25 7450);
FORCEPROP 1 LASTPIN (25 7275) $PN 1
J 0
(37 7287);
DISPLAY 0.787234 (37 7287);
PAINT MONO (37 7287);
FORCEPROP 1 LASTPIN (225 7275) $PN 2
J 0
(187 7287);
DISPLAY 0.787234 (187 7287);
PAINT MONO (187 7287);
FORCEPROP 1 LAST MATERIAL CHIP
J 0
(350 7275);
DISPLAY 0.510638 (350 7275);
FORCEPROP 1 LAST TOLERANCE 5%
J 0
(300 7275);
DISPLAY 0.510638 (300 7275);
FORCEPROP 0 LAST ROOM NIC_P3V3_BOM2
J 0
(-25 7400);
DISPLAY 0.680851 (-25 7400);
PAINT RED (-25 7400);
FORCEPROP 1 LAST VALUE 0
J 2
(275 7275);
DISPLAY 0.510638 (275 7275);
FORCEPROP 2 LAST CDS_LIB pure_quanta
J 0
(125 7275);
DISPLAY INVISIBLE (125 7275);
FORCEPROP 1 LAST PACK_TYPE 0402LF
J 0
(375 7275);
DISPLAY 0.510638 (375 7275);
DISPLAY INVISIBLE (375 7275);
FORCEPROP 1 LAST WATTAGE 1/16W
J 2
(225 7200);
DISPLAY 0.319149 (225 7200);
DISPLAY INVISIBLE (225 7200);
FORCEPROP 1 LAST PATH I80
J 0
(75 7425);
DISPLAY 0.978723 (75 7425);
PAINT WHITE (75 7425);
DISPLAY INVISIBLE (75 7425);
FORCEPROP 1 LAST PART_NUMBER CS00002JB13
J 0
(50 7225);
DISPLAY 0.319149 (50 7225);
DISPLAY INVISIBLE (50 7225);
FORCEADD OFFPAGE..1
(-1125 7275);
PAINT AQUA (-1125 7275);
FORCEPROP 2 LAST $XR3 248 
J 0
(-1737 7275);
DISPLAY 0.638298 (-1737 7275);
PAINT MONO (-1737 7275);
FORCEPROP 2 LAST $XR2 141 
J 0
(-1617 7275);
DISPLAY 0.638298 (-1617 7275);
PAINT MONO (-1617 7275);
FORCEPROP 2 LAST $XR1 140 
J 0
(-1497 7275);
DISPLAY 0.638298 (-1497 7275);
PAINT MONO (-1497 7275);
FORCEPROP 2 LAST $XR0 142 
J 0
(-1377 7275);
DISPLAY 0.638298 (-1377 7275);
PAINT MONO (-1377 7275);
FORCEPROP 2 LAST CDS_LIB standard
J 0
(-1125 7275);
DISPLAY INVISIBLE (-1125 7275);
FORCEPROP 1 LAST OFFPAGE TRUE
J 0
(-800 7150);
DISPLAY 0.872340 (-800 7150);
PAINT AQUA (-800 7150);
DISPLAY INVISIBLE (-800 7150);
FORCEPROP 1 LAST COMMENT_BODY TRUE
J 0
(-1000 7175);
DISPLAY 0.872340 (-1000 7175);
PAINT GREEN (-1000 7175);
DISPLAY INVISIBLE (-1000 7175);
FORCEPROP 2 LAST PATH I81
J 0
(-1075 7350);
DISPLAY 0.680851 (-1075 7350);
DISPLAY INVISIBLE (-1075 7350);
FORCEADD RS31312R..1
(-1975 2925);
FORCEPROP 1 LAST LOCATION PU206
J 0
(-2225 3550);
DISPLAY 0.723404 (-2225 3550);
PAINT GREEN (-2225 3550);
FORCEPROP 2 LAST SEC 1
J 0
(-2200 3675);
DISPLAY 0.680851 (-2200 3675);
PAINT MONO (-2200 3675);
DISPLAY INVISIBLE (-2200 3675);
FORCEPROP 2 LASTPIN (-1575 2800) $PN 12
J 0
(-1565 2810);
DISPLAY 0.680851 (-1565 2810);
PAINT MONO (-1565 2810);
FORCEPROP 2 LASTPIN (-2375 3050) $PN 1
J 2
(-2385 3060);
DISPLAY 0.680851 (-2385 3060);
PAINT MONO (-2385 3060);
FORCEPROP 2 LASTPIN (-2375 2850) $PN 3
J 2
(-2385 2860);
DISPLAY 0.680851 (-2385 2860);
PAINT MONO (-2385 2860);
FORCEPROP 2 LASTPIN (-1575 2550) $PN 9
J 0
(-1565 2560);
DISPLAY 0.680851 (-1565 2560);
PAINT MONO (-1565 2560);
FORCEPROP 2 LASTPIN (-2375 2450) $PN 7
J 2
(-2385 2460);
DISPLAY 0.680851 (-2385 2460);
PAINT MONO (-2385 2460);
FORCEPROP 2 LASTPIN (-1575 2450) $PN 8
J 0
(-1565 2460);
DISPLAY 0.680851 (-1565 2460);
PAINT MONO (-1565 2460);
FORCEPROP 2 LASTPIN (-2375 2650) $PN 5
J 2
(-2385 2660);
DISPLAY 0.680851 (-2385 2660);
PAINT MONO (-2385 2660);
FORCEPROP 2 LASTPIN (-2375 2950) $PN 2
J 2
(-2385 2960);
DISPLAY 0.680851 (-2385 2960);
PAINT MONO (-2385 2960);
FORCEPROP 2 LASTPIN (-1575 2700) $PN 11
J 0
(-1565 2710);
DISPLAY 0.680851 (-1565 2710);
PAINT MONO (-1565 2710);
FORCEPROP 2 LASTPIN (-1575 3400) $PN 10
J 0
(-1565 3410);
DISPLAY 0.680851 (-1565 3410);
PAINT MONO (-1565 3410);
FORCEPROP 2 LASTPIN (-2375 2550) $PN 6
J 2
(-2385 2560);
DISPLAY 0.680851 (-2385 2560);
PAINT MONO (-2385 2560);
FORCEPROP 2 LASTPIN (-2375 2750) $PN 4
J 2
(-2385 2760);
DISPLAY 0.680851 (-2385 2760);
PAINT MONO (-2385 2760);
FORCEPROP 2 LASTPIN (-2375 3400) $PN 21_22
J 2
(-2385 3410);
DISPLAY 0.680851 (-2385 3410);
PAINT MONO (-2385 3410);
FORCEPROP 2 LASTPIN (-2375 3350) $PN 23
J 2
(-2385 3360);
DISPLAY 0.680851 (-2385 3360);
PAINT MONO (-2385 3360);
FORCEPROP 2 LASTPIN (-2375 3300) $PN 24
J 2
(-2385 3310);
DISPLAY 0.680851 (-2385 3310);
PAINT MONO (-2385 3310);
FORCEPROP 2 LASTPIN (-2375 3250) $PN 25
J 2
(-2385 3260);
DISPLAY 0.680851 (-2385 3260);
PAINT MONO (-2385 3260);
FORCEPROP 2 LASTPIN (-2375 3200) $PN 26
J 2
(-2385 3210);
DISPLAY 0.680851 (-2385 3210);
PAINT MONO (-2385 3210);
FORCEPROP 2 LASTPIN (-1575 2900) $PN 13
J 0
(-1565 2910);
DISPLAY 0.680851 (-1565 2910);
PAINT MONO (-1565 2910);
FORCEPROP 2 LASTPIN (-1575 2950) $PN 14
J 0
(-1565 2960);
DISPLAY 0.680851 (-1565 2960);
PAINT MONO (-1565 2960);
FORCEPROP 2 LASTPIN (-1575 3000) $PN 15
J 0
(-1565 3010);
DISPLAY 0.680851 (-1565 3010);
PAINT MONO (-1565 3010);
FORCEPROP 2 LASTPIN (-1575 3050) $PN 16
J 0
(-1565 3060);
DISPLAY 0.680851 (-1565 3060);
PAINT MONO (-1565 3060);
FORCEPROP 2 LASTPIN (-1575 3100) $PN 17
J 0
(-1565 3110);
DISPLAY 0.680851 (-1565 3110);
PAINT MONO (-1565 3110);
FORCEPROP 2 LASTPIN (-1575 3150) $PN 18
J 0
(-1565 3160);
DISPLAY 0.680851 (-1565 3160);
PAINT MONO (-1565 3160);
FORCEPROP 2 LASTPIN (-1575 3200) $PN 19
J 0
(-1565 3210);
DISPLAY 0.680851 (-1565 3210);
PAINT MONO (-1565 3210);
FORCEPROP 2 LASTPIN (-1575 3250) $PN 20
J 0
(-1565 3260);
DISPLAY 0.680851 (-1565 3260);
PAINT MONO (-1565 3260);
FORCEPROP 0 LAST ROOM NIC_P12V_MPS_MAM_BOM2
J 0
(-2200 3725);
DISPLAY 0.680851 (-2200 3725);
PAINT RED (-2200 3725);
FORCEPROP 2 LAST VALUE RS31312R
J 0
(-2203 3589);
DISPLAY 0.680851 (-2203 3589);
FORCEPROP 2 LAST PART_TYPE SMLF
J 0
(-2203 3639);
DISPLAY 0.680851 (-2203 3639);
FORCEPROP 1 LAST MATERIAL IC
J 0
(-2222 3462);
DISPLAY 0.723404 (-2222 3462);
PAINT GREEN (-2222 3462);
FORCEPROP 2 LAST SEC_TYPE 
J 0
(-2200 3675);
DISPLAY 0.680851 (-2200 3675);
DISPLAY INVISIBLE (-2200 3675);
FORCEPROP 2 LAST CDS_LIB pure_quanta
J 0
(-1975 2925);
DISPLAY INVISIBLE (-1975 2925);
FORCEPROP 1 LAST NEEDS_NO_SIZE TRUE
J 0
(-1975 2925);
DISPLAY 0.723404 (-1975 2925);
PAINT GREEN (-1975 2925);
DISPLAY INVISIBLE (-1975 2925);
FORCEPROP 1 LAST CDS_LMAN_SYM_OUTLINE -250,525,250,-525
J 0
(-1975 2925);
DISPLAY 0.468085 (-1975 2925);
PAINT GREEN (-1975 2925);
DISPLAY INVISIBLE (-1975 2925);
FORCEPROP 1 LAST PATH I82
J 0
(-1975 2925);
DISPLAY 0.723404 (-1975 2925);
PAINT GREEN (-1975 2925);
DISPLAY INVISIBLE (-1975 2925);
FORCEPROP 1 LAST PART_NUMBER AL031312000
J 0
(-2225 3500);
DISPLAY 0.723404 (-2225 3500);
PAINT GREEN (-2225 3500);
DISPLAY INVISIBLE (-2225 3500);
FORCEADD OFFPAGE..1
(-4325 3050);
PAINT AQUA (-4325 3050);
FORCEPROP 2 LAST $XR3 142 
J 0
(-4906 3050);
DISPLAY 0.638298 (-4906 3050);
PAINT MONO (-4906 3050);
FORCEPROP 2 LAST $XR2 140 
J 0
(-4786 3050);
DISPLAY 0.638298 (-4786 3050);
PAINT MONO (-4786 3050);
FORCEPROP 2 LAST $XR1 83 
J 0
(-4666 3050);
DISPLAY 0.638298 (-4666 3050);
PAINT MONO (-4666 3050);
FORCEPROP 2 LAST $XR0 81 
J 0
(-4576 3050);
DISPLAY 0.638298 (-4576 3050);
PAINT MONO (-4576 3050);
FORCEPROP 2 LAST CDS_LIB standard
J 0
(-4325 3050);
DISPLAY INVISIBLE (-4325 3050);
FORCEPROP 1 LAST OFFPAGE TRUE
J 0
(-4000 2925);
DISPLAY 0.872340 (-4000 2925);
PAINT AQUA (-4000 2925);
DISPLAY INVISIBLE (-4000 2925);
FORCEPROP 1 LAST COMMENT_BODY TRUE
J 0
(-4200 2950);
DISPLAY 0.872340 (-4200 2950);
PAINT GREEN (-4200 2950);
DISPLAY INVISIBLE (-4200 2950);
FORCEPROP 2 LAST PATH I9
J 0
(-4575 3100);
DISPLAY 1.021277 (-4575 3100);
DISPLAY INVISIBLE (-4575 3100);
FORCEADD DNS..2
(450 1950);
PAINT RED (450 1950);
FORCEPROP 2 LAST CDS_LIB mstr_misc
J 0
(450 1950);
DISPLAY INVISIBLE (450 1950);
FORCEPROP 1 LAST COMMENT_BODY TRUE
R 1
J 0
(525 1725);
DISPLAY 0.872340 (525 1725);
PAINT GREEN (525 1725);
DISPLAY INVISIBLE (525 1725);
FORCEADD DNS..2
(-375 3000);
PAINT RED (-375 3000);
FORCEPROP 2 LAST CDS_LIB mstr_misc
J 0
(-375 3000);
DISPLAY INVISIBLE (-375 3000);
FORCEPROP 1 LAST COMMENT_BODY TRUE
R 1
J 0
(-300 2775);
DISPLAY 0.872340 (-300 2775);
PAINT GREEN (-300 2775);
DISPLAY INVISIBLE (-300 2775);
FORCEADD DNS..2
(-3475 3075);
PAINT RED (-3475 3075);
FORCEPROP 2 LAST CDS_LIB mstr_misc
J 0
(-3475 3075);
DISPLAY INVISIBLE (-3475 3075);
FORCEPROP 1 LAST COMMENT_BODY TRUE
R 1
J 0
(-3400 2850);
DISPLAY 0.872340 (-3400 2850);
PAINT GREEN (-3400 2850);
DISPLAY INVISIBLE (-3400 2850);
FORCEADD CAD_NOTE..1
(1550 2300);
FORCEPROP 0 LAST S1 R3873/R3874 CO-LAYOUT
J 0
(1425 2175);
DISPLAY 0.808511 (1425 2175);
PAINT WHITE (1425 2175);
FORCEPROP 2 LAST CDS_LIB pure_quanta_power
J 0
(1550 2300);
DISPLAY INVISIBLE (1550 2300);
FORCEPROP 1 LAST COMMENT_BODY TRUE
J 0
(1575 2400);
DISPLAY 0.978723 (1575 2400);
DISPLAY INVISIBLE (1575 2400);
FORCEADD DNS..2
(225 6500);
PAINT RED (225 6500);
FORCEPROP 2 LAST CDS_LIB mstr_misc
J 0
(225 6500);
DISPLAY INVISIBLE (225 6500);
FORCEPROP 1 LAST COMMENT_BODY TRUE
R 1
J 0
(300 6275);
DISPLAY 0.872340 (300 6275);
PAINT GREEN (300 6275);
DISPLAY INVISIBLE (300 6275);
FORCEADD DNS..2
(250 6825);
PAINT RED (250 6825);
FORCEPROP 2 LAST CDS_LIB mstr_misc
J 0
(250 6825);
DISPLAY INVISIBLE (250 6825);
FORCEPROP 1 LAST COMMENT_BODY TRUE
R 1
J 0
(325 6600);
DISPLAY 0.872340 (325 6600);
PAINT GREEN (325 6600);
DISPLAY INVISIBLE (325 6600);
FORCEADD QUANTA_TITLE_BLOCK_C..1
(3575 1425);
FORCEPROP 0 LAST CDS_CON_LAST_MODIFIED Thu Sep 14 16:12:26 2023
J 0
(1690 1440);
DISPLAY INVISIBLE (1690 1440);
FORCEPROP 2 LAST CUSTOM_TXT_CDS <XR_PAGE_TITLE>
J 0
(-4315 6675);
DISPLAY 0.638298 (-4315 6675);
PAINT PINK (-4315 6675);
DISPLAY INVISIBLE (-4315 6675);
FORCEPROP 2 LAST CUSTOM_TXT_CDS <CON_LAST_MODIFIED>
J 0
(1690 1440);
DISPLAY 0.978723 (1690 1440);
FORCEPROP 2 LAST CUSTOM_TXT_CDS <Q_PROJ>
J 0
(1193 1527);
DISPLAY 1.212766 (1193 1527);
FORCEPROP 2 LAST CUSTOM_TXT_CDS <CON_PAGE_NUM> OF <CON_TOTAL_PAGES>
J 0
(3129 1443);
DISPLAY 0.978723 (3129 1443);
FORCEPROP 2 LAST CUSTOM_TXT_CDS <Q_REV>
J 0
(3391 1528);
DISPLAY 1.212766 (3391 1528);
FORCEPROP 2 LAST CUSTOM_TXT_CDS <Q_NUMBER>
J 0
(2172 1528);
DISPLAY 1.212766 (2172 1528);
FORCEPROP 2 LAST CUSTOM_TXT_CDS <NAME_1>
J 0
(400 1600);
FORCEPROP 2 LAST CUSTOM_TXT_CDS <NAME_2>
J 0
(400 1475);
FORCEPROP 1 LAST Q_TITLE V3_2_OCP3.0 HSC-CO-LAYOUT(2/3)
J 0
(-5741 1476);
DISPLAY 2.446809 (-5741 1476);
PAINT GREEN (-5741 1476);
FORCEPROP 2 LAST PAGE_BORDER TRUE
J 0
(-4315 6675);
DISPLAY 0.638298 (-4315 6675);
PAINT PINK (-4315 6675);
DISPLAY INVISIBLE (-4315 6675);
FORCEPROP 1 LAST CDS_LMAN_SYM_OUTLINE -9475,6775,100,-125
J 0
(3575 1425);
DISPLAY 0.468085 (3575 1425);
PAINT GREEN (3575 1425);
DISPLAY INVISIBLE (3575 1425);
FORCEPROP 2 LAST CDS_LIB pure_quanta
J 0
(3575 1425);
DISPLAY INVISIBLE (3575 1425);
FORCEPROP 2 LAST CDS_XR_PAGE_TITLE CR-141 : @T6G_MB_LIB.T6G(SCH_1):PAGE141
J 0
(-4315 6675);
DISPLAY 0.638298 (-4315 6675);
PAINT PINK (-4315 6675);
DISPLAY INVISIBLE (-4315 6675);
FORCEPROP 1 LAST Q_DEPT BU9
J 1
(-188 1474);
DISPLAY 1.957447 (-188 1474);
PAINT GREEN (-188 1474);
DISPLAY INVISIBLE (-188 1474);
FORCEPROP 1 LAST COMMENT_BODY TRUE
J 0
(3587 1412);
DISPLAY 0.978723 (3587 1412);
PAINT GREEN (3587 1412);
DISPLAY INVISIBLE (3587 1412);
FORCEADD DNS..2
(-925 3000);
PAINT RED (-925 3000);
FORCEPROP 2 LAST CDS_LIB mstr_misc
J 0
(-925 3000);
DISPLAY INVISIBLE (-925 3000);
FORCEPROP 1 LAST COMMENT_BODY TRUE
R 1
J 0
(-850 2775);
DISPLAY 0.872340 (-850 2775);
PAINT GREEN (-850 2775);
DISPLAY INVISIBLE (-850 2775);
WIRE 16 -1 (-3600 2300)(-3600 2500);
WIRE 16 -1 (-2925 3225)(-2925 3450);
WIRE 16 -1 (-750 2550)(-580 2550);
WIRE 16 -1 (-580 2550)(-580 2558);
WIRE 16 -1 (-1475 3775)(-1475 3700);
WIRE 16 -1 (-3175 2225)(-3175 2350);
WIRE 16 -1 (1050 3100)(1050 3000);
WIRE 16 -1 (495 6058)(495 5933);
WIRE 16 -1 (750 6650)(750 6600);
WIRE 16 -1 (870 6008)(870 5933);
WIRE 16 -1 (-2755 2183)(-2755 2283);
WIRE 16 -1 (2900 6050)(2900 6250);
WIRE 16 -1 (2075 6575)(2900 6575);
WIRE 16 -1 (2900 6575)(2900 6850);
WIRE 16 -1 (2900 6575)(2900 6450);
WIRE 16 -1 (-2375 3200)(-2455 3200);
WIRE 16 -1 (-2455 3200)(-2455 3250);
WIRE 16 -1 (-2375 3250)(-2455 3250);
WIRE 16 -1 (-2455 3250)(-2455 3300);
WIRE 16 -1 (-2455 3300)(-2455 3350);
WIRE 16 -1 (-2375 3300)(-2455 3300);
WIRE 16 -1 (-2375 3350)(-2455 3350);
WIRE 16 -1 (-2455 3350)(-2455 3400);
WIRE 16 -1 (-2455 3400)(-2375 3400);
WIRE 16 -1 (-2475 3400)(-2455 3400);
WIRE 16 -1 (-2475 3825)(-2475 3400);
WIRE 16 -1 (-2925 3825)(-2475 3825);
WIRE 16 -1 (-2925 3925)(-2925 3825);
WIRE 16 -1 (-2925 3650)(-2925 3825);
WIRE 16 -1 (-1575 2900)(-1268 2900);
WIRE 16 -1 (-1268 2900)(-1268 2950);
WIRE 16 -1 (-1268 2950)(-1268 3000);
WIRE 16 -1 (-1575 2950)(-1268 2950);
WIRE 16 -1 (-1268 3000)(-1268 3050);
WIRE 16 -1 (-1575 3000)(-1268 3000);
WIRE 16 -1 (-1268 3050)(-1268 3100);
WIRE 16 -1 (-1268 3050)(-1575 3050);
WIRE 16 -1 (-1268 3100)(-1268 3150);
WIRE 16 -1 (-1575 3100)(-1268 3100);
WIRE 16 -1 (-1268 3150)(-1268 3200);
WIRE 16 -1 (-1575 3150)(-1268 3150);
WIRE 16 -1 (-1268 3200)(-1268 3250);
WIRE 16 -1 (-1575 3200)(-1268 3200);
WIRE 16 -1 (-1268 3250)(-925 3250);
WIRE 16 -1 (-1575 3250)(-1268 3250);
WIRE 16 -1 (-925 3250)(-375 3250);
WIRE 16 -1 (-925 3125)(-925 3250);
WIRE 16 -1 (-375 3250)(-375 3375);
WIRE 16 -1 (-375 3125)(-375 3250);
WIRE 16 -1 (-375 3375)(1050 3375);
WIRE 16 -1 (1050 3375)(1050 3450);
WIRE 16 -1 (1050 3300)(1050 3375);
WIRE 16 -1 (-825 2800)(-925 2800);
WIRE 16 -1 (-925 2925)(-925 2800);
WIRE 16 -1 (-1575 2800)(-925 2800);
FORCEPROP 2 LAST SIG_NAME P12V_OCP_AVIN_PD_2
J 0
(-1485 2810);
DISPLAY 0.574468 (-1485 2810);
WIRE 16 -1 (20 2858)(20 2700);
WIRE 16 -1 (20 2700)(20 2633);
WIRE 16 -1 (20 2700)(-375 2700);
WIRE 16 -1 (-375 2925)(-375 2700);
WIRE 16 -1 (-1575 2700)(-375 2700);
FORCEPROP 2 LAST SIG_NAME P12V_OCP_OV_FB_2
J 0
(-1485 2710);
DISPLAY 0.574468 (-1485 2710);
FORCEPROP 2 LASTPROP $XRERR UNIQUE?
J 0
(-1725 2710);
DISPLAY 0.638298 (-1725 2710);
PAINT MONO (-1725 2710);
DISPLAY INVISIBLE (-1725 2710);
WIRE 16 -1 (-1475 3500)(-1475 3400);
FORCEPROP 2 LAST SIG_NAME HP_LVC3_OCP_V3_2_P12V_PWRGD
J 0
(-1410 3410);
DISPLAY 0.574468 (-1410 3410);
WIRE 16 -1 (-1475 3400)(-725 3400);
WIRE 16 -1 (-1575 3400)(-1475 3400);
WIRE 16 -1 (-950 2550)(-1575 2550);
FORCEPROP 2 LAST SIG_NAME P12V_OCP_FLTB_2
J 0
(-1485 2560);
DISPLAY 0.574468 (-1485 2560);
FORCEPROP 2 LASTPROP $XRERR UNIQUE?
J 0
(-1725 2560);
DISPLAY 0.638298 (-1725 2560);
PAINT MONO (-1725 2560);
DISPLAY INVISIBLE (-1725 2560);
WIRE 16 -1 (-25 1950)(325 1950);
WIRE 16 -1 (-25 2075)(-25 1950);
WIRE 16 -1 (-25 2075)(325 2075);
WIRE 16 -1 (-25 2075)(-375 2075);
WIRE 16 -1 (-375 2450)(-375 2075);
WIRE 16 -1 (-975 2450)(-375 2450);
WIRE 16 -1 (-975 2300)(-975 2450);
WIRE 16 -1 (-1425 2450)(-975 2450);
WIRE 16 -1 (-1425 2300)(-1425 2450);
WIRE 16 -1 (-1575 2450)(-1425 2450);
FORCEPROP 2 LAST SIG_NAME P12V_OCP_IMON_2
J 0
(-1480 2458);
DISPLAY 0.574468 (-1480 2458);
FORCEPROP 2 LASTPROP $XRERR UNIQUE?
J 0
(-1720 2458);
DISPLAY 0.638298 (-1720 2458);
PAINT MONO (-1720 2458);
DISPLAY INVISIBLE (-1720 2458);
WIRE 16 -1 (-3350 3500)(-3150 3500);
WIRE 16 -1 (-3150 3500)(-3150 3050);
WIRE 16 -1 (-2375 3050)(-3150 3050);
FORCEPROP 2 LAST SIG_NAME P12V_OCP_V3_2_EN_2_R3
J 0
(-3055 3050);
DISPLAY 0.574468 (-3055 3050);
FORCEPROP 2 LASTPROP $XRERR UNIQUE?
J 0
(-3295 3050);
DISPLAY 0.638298 (-3295 3050);
PAINT MONO (-3295 3050);
DISPLAY INVISIBLE (-3295 3050);
WIRE 16 -1 (-3150 3050)(-3400 3050);
WIRE 16 -1 (-2375 2950)(-2725 2950);
WIRE 16 -1 (-2725 2950)(-2725 2850);
WIRE 16 -1 (-2725 2850)(-2375 2850);
WIRE 16 -1 (-2725 2850)(-3200 2850);
WIRE 16 -1 (-2375 2750)(-3600 2750);
FORCEPROP 2 LAST SIG_NAME P12V_OCP_TIMER_2
J 0
(-2885 2760);
DISPLAY 0.574468 (-2885 2760);
FORCEPROP 2 LASTPROP $XRERR UNIQUE?
J 0
(-3125 2760);
DISPLAY 0.638298 (-3125 2760);
PAINT MONO (-3125 2760);
DISPLAY INVISIBLE (-3125 2760);
WIRE 16 -1 (-3600 2750)(-3600 2700);
WIRE 16 -1 (-2375 2650)(-3175 2650);
FORCEPROP 2 LAST SIG_NAME P12V_OCP_ISET_2
J 0
(-2860 2660);
DISPLAY 0.574468 (-2860 2660);
FORCEPROP 2 LASTPROP $XRERR UNIQUE?
J 0
(-3100 2660);
DISPLAY 0.638298 (-3100 2660);
PAINT MONO (-3100 2660);
DISPLAY INVISIBLE (-3100 2660);
WIRE 16 -1 (-3175 2550)(-3175 2650);
WIRE 16 -1 (-2375 2550)(-2755 2550);
FORCEPROP 2 LAST SIG_NAME P12V_OCP_SS_2
J 0
(-2810 2560);
DISPLAY 0.574468 (-2810 2560);
FORCEPROP 2 LASTPROP $XRERR UNIQUE?
J 0
(-3050 2560);
DISPLAY 0.638298 (-3050 2560);
PAINT MONO (-3050 2560);
DISPLAY INVISIBLE (-3050 2560);
WIRE 16 -1 (-2755 2483)(-2755 2550);
WIRE 16 -1 (-2434 2450)(-2375 2450);
WIRE 16 -1 (-2434 2366)(-2434 2450);
WIRE 16 -1 (-1425 2100)(-1425 1950);
WIRE 16 -1 (-1425 1950)(-975 1950);
WIRE 16 -1 (-975 1950)(-975 2100);
WIRE 16 -1 (-975 1950)(-975 1875);
WIRE 16 -1 (20 2433)(20 2283);
WIRE 16 -1 (20 2283)(220 2283);
WIRE 16 -1 (220 2283)(550 2283);
WIRE 16 -1 (220 2283)(220 2258);
WIRE 16 -1 (550 2283)(550 2425);
WIRE 16 -1 (150 6075)(150 5958);
WIRE 16 -1 (150 5958)(-250 5958);
WIRE 16 -1 (-250 5958)(-250 6075);
WIRE 16 -1 (-250 5958)(-250 5925);
WIRE 16 -1 (20 3058)(20 3133);
WIRE 16 -1 (20 3133)(500 3133);
WIRE 16 -1 (500 3133)(550 3133);
WIRE 16 -1 (500 3175)(500 3133);
WIRE 16 -1 (550 3133)(550 3050);
WIRE 16 -1 (1150 6950)(1150 6575);
WIRE 16 -1 (825 6950)(1150 6950);
WIRE 16 -1 (1150 6575)(1275 6575);
WIRE 16 -1 (825 7075)(825 6950);
WIRE 16 -1 (750 6950)(825 6950);
WIRE 16 -1 (750 6850)(750 6950);
WIRE 16 -1 (2225 6275)(2075 6275);
WIRE 16 -1 (2225 6275)(2225 5975);
WIRE 16 -1 (2225 5975)(2500 5975);
WIRE 16 -1 (2500 6050)(2500 5975);
WIRE 16 -1 (2500 5975)(2500 5850);
WIRE 16 -1 (525 1950)(1625 1950);
FORCEPROP 2 LAST SIG_NAME P12V_OCP_V3_2_ISENSE_MPS_TIC
J 0
(815 1960);
DISPLAY 0.574468 (815 1960);
WIRE 16 2175 (50 2175)(775 2175);
WIRE 16 2175 (50 2175)(50 1875);
WIRE 16 2175 (775 2175)(775 1875);
WIRE 16 2175 (50 1875)(775 1875);
WIRE 16 -1 (525 2075)(1625 2075);
FORCEPROP 2 LAST SIG_NAME P12V_OCP_V3_2_ISENSE_MPS_MAM
J 0
(815 2085);
DISPLAY 0.574468 (815 2085);
WIRE 16 -1 (550 2625)(550 2700);
WIRE 16 -1 (1425 2700)(550 2700);
FORCEPROP 2 LAST SIG_NAME P12V_OCP_AVIN_PD_2
J 0
(940 2710);
DISPLAY 0.574468 (940 2710);
WIRE 16 -1 (550 2700)(550 2850);
WIRE 16 3135 (-875 4500)(375 4500);
WIRE 16 3135 (-875 3850)(-875 4500);
WIRE 16 3135 (375 3850)(375 4500);
WIRE 16 3135 (-875 3850)(375 3850);
WIRE 16 3135 (-500 4475)(-500 3875);
WIRE 16 3135 (-850 3950)(350 3950);
WIRE 16 3135 (-850 4050)(350 4050);
WIRE 16 3135 (-850 4250)(350 4250);
WIRE 16 3135 (-850 4350)(350 4350);
WIRE 16 -1 (-250 6275)(-250 6375);
WIRE 16 -1 (-250 6375)(150 6375);
WIRE 16 -1 (1275 6375)(150 6375);
FORCEPROP 2 LAST SIG_NAME P3V3_OCP_MODE_2
J 0
(765 6385);
DISPLAY 0.574468 (765 6385);
FORCEPROP 2 LASTPROP $XRERR UNIQUE?
J 0
(525 6385);
DISPLAY 0.638298 (525 6385);
PAINT MONO (525 6385);
DISPLAY INVISIBLE (525 6385);
WIRE 16 -1 (150 6275)(150 6375);
WIRE 16 -1 (25 7275)(-1075 7275);
FORCEPROP 2 LAST SIG_NAME P12V_OCP_V3_2_BUF_EN_R
J 0
(-935 7285);
DISPLAY 0.680851 (-935 7285);
WIRE 16 -1 (225 7275)(600 7275);
WIRE 16 -1 (600 7275)(600 6850);
WIRE 16 -1 (600 6850)(600 6475);
WIRE 16 -1 (325 6850)(600 6850);
WIRE 16 -1 (1275 6475)(600 6475);
FORCEPROP 2 LAST SIG_NAME P3V3_OCP_EN_2
J 0
(815 6485);
DISPLAY 0.574468 (815 6485);
FORCEPROP 2 LASTPROP $XRERR UNIQUE?
J 0
(575 6485);
DISPLAY 0.638298 (575 6485);
PAINT MONO (575 6485);
DISPLAY INVISIBLE (575 6485);
WIRE 16 -1 (600 6475)(325 6475);
WIRE 16 -1 (125 6850)(-1100 6850);
FORCEPROP 2 LAST SIG_NAME HP_LVC3_OCP_V3_2_P12V_PWRGD
J 0
(-885 6885);
DISPLAY 0.680851 (-885 6885);
WIRE 16 -1 (125 6475)(-1100 6475);
FORCEPROP 2 LAST SIG_NAME P3V3_OCP_V3_2_EN_R
J 0
(-1010 6485);
DISPLAY 0.808511 (-1010 6485);
WIRE 16 3135 (-75 4475)(-75 3875);
WIRE 16 -1 (-3600 3050)(-4275 3050);
FORCEPROP 2 LAST SIG_NAME P12V_OCP_V3_2_EN_R
J 0
(-4210 3060);
DISPLAY 0.638298 (-4210 3060);
WIRE 16 -1 (-3550 3500)(-4450 3500);
FORCEPROP 2 LAST SIG_NAME P12V_OCP_V3_2_BUF_EN_R
J 0
(-4410 3510);
DISPLAY 0.680851 (-4410 3510);
WIRE 16 3135 (-850 4150)(350 4150);
WIRE 16 -1 (495 6258)(495 6325);
WIRE 16 -1 (495 6325)(1275 6325);
FORCEPROP 2 LAST SIG_NAME P3V3_OCP_ILIMIT_2
J 0
(765 6335);
DISPLAY 0.510638 (765 6335);
FORCEPROP 2 LASTPROP $XRERR UNIQUE?
J 0
(525 6335);
DISPLAY 0.638298 (525 6335);
PAINT MONO (525 6335);
DISPLAY INVISIBLE (525 6335);
WIRE 16 -1 (870 6275)(1275 6275);
WIRE 16 -1 (870 6208)(870 6275);
FORCEPROP 2 LAST SIG_NAME P3V3_OCP_DVDT_2
J 0
(765 6285);
DISPLAY 0.574468 (765 6285);
FORCEPROP 2 LASTPROP $XRERR UNIQUE?
J 0
(525 6285);
DISPLAY 0.638298 (525 6285);
PAINT MONO (525 6285);
DISPLAY INVISIBLE (525 6285);
WIRE 16 -1 (2500 6375)(2500 6250);
WIRE 16 -1 (2075 6375)(2500 6375);
FORCEPROP 2 LAST SIG_NAME P3V3_OCP_GATE_PU207_2
J 0
(2156 6400);
DISPLAY 0.574468 (2156 6400);
FORCEPROP 2 LASTPROP $XRERR UNIQUE?
J 0
(1916 6400);
DISPLAY 0.638298 (1916 6400);
PAINT MONO (1916 6400);
DISPLAY INVISIBLE (1916 6400);
WIRE 16 2175 (-5500 6700)(-3797 6700);
WIRE 16 2175 (-5500 7600)(-5500 6700);
WIRE 16 2175 (-3797 7600)(-3797 6700);
WIRE 16 2175 (-5500 7600)(-3797 7600);
DOT 1 (220 2283);
DOT 1 (-25 2075);
DOT 1 (600 6850);
DOT 1 (825 6950);
DOT 1 (-250 5958);
DOT 1 (20 2700);
DOT 1 (-975 2450);
DOT 1 (1050 3375);
DOT 1 (-925 3250);
DOT 1 (500 3133);
DOT 1 (-1268 3250);
DOT 1 (-375 3250);
DOT 1 (600 6475);
DOT 1 (2900 6575);
DOT 1 (-1425 2450);
DOT 1 (2500 5975);
DOT 1 (550 2700);
DOT 1 (-2455 3400);
DOT 1 (-975 1950);
DOT 1 (150 6375);
DOT 1 (-1475 3400);
DOT 1 (-2455 3350);
DOT 1 (-2455 3300);
DOT 1 (-2455 3250);
DOT 1 (-1268 3200);
DOT 1 (-1268 3150);
DOT 1 (-1268 3100);
DOT 1 (-1268 3050);
DOT 1 (-3150 3050);
DOT 1 (-1268 3000);
DOT 1 (-1268 2950);
DOT 1 (-2725 2850);
DOT 1 (-925 2800);
DOT 1 (-375 2700);
DOT 1 (-2925 3825);
FORCENOTE
P12V_OCP_V3_2
(-5425 7000) 0;
DISPLAY LEFT (-5425 7000);
DISPLAY 1.021277 (-5425 7000);
FORCENOTE
START UP TIME:4.7MS
(1200 5675) 0;
DISPLAY LEFT (1200 5675);
DISPLAY 1.021277 (1200 5675);
PAINT WHITE (1200 5675);
FORCENOTE
START UP TIME:8.62MS
(-3175 2000) 0;
DISPLAY LEFT (-3175 2000);
DISPLAY 1.021277 (-3175 2000);
PAINT WHITE (-3175 2000);
FORCENOTE
PR3857
(-800 3975) 0;
DISPLAY LEFT (-800 3975);
DISPLAY 1.021277 (-800 3975);
FORCENOTE
PR3852
(-800 4175) 0;
DISPLAY LEFT (-800 4175);
DISPLAY 1.021277 (-800 4175);
FORCENOTE
2ND SOURCE OF PU200
(1100 7150) 0;
DISPLAY LEFT (1100 7150);
DISPLAY 1.276596 (1100 7150);
FORCENOTE
MP5025A/
(-25 4425) 0;
DISPLAY LEFT (-25 4425);
DISPLAY 1.021277 (-25 4425);
FORCENOTE
DE-POP
(-25 3875) 0;
DISPLAY LEFT (-25 3875);
DISPLAY 1.021277 (-25 3875);
FORCENOTE
POP
(-450 3875) 0;
DISPLAY LEFT (-450 3875);
DISPLAY 1.021277 (-450 3875);
FORCENOTE
POP
(-450 3975) 0;
DISPLAY LEFT (-450 3975);
DISPLAY 1.021277 (-450 3975);
FORCENOTE
MP5022A
(-25 4375) 0;
DISPLAY LEFT (-25 4375);
DISPLAY 1.021277 (-25 4375);
FORCENOTE
FROM CPLD
(-4725 3125) 0;
DISPLAY LEFT (-4725 3125);
DISPLAY 1.021277 (-4725 3125);
FORCENOTE
FROM PRSNT BUFFER
(-4725 3375) 0;
DISPLAY LEFT (-4725 3375);
DISPLAY 1.021277 (-4725 3375);
FORCENOTE
VTH>1.391V(HIGH)
(-4700 2809) 0;
DISPLAY LEFT (-4700 2809);
DISPLAY 1.021277 (-4700 2809);
PAINT WHITE (-4700 2809);
FORCENOTE
PU206 OPTIONAL BOM
(-850 4525) 0;
DISPLAY LEFT (-850 4525);
DISPLAY 1.021277 (-850 4525);
FORCENOTE
=1.6A
(250 5650) 0;
DISPLAY LEFT (250 5650);
DISPLAY 1.021277 (250 5650);
PAINT WHITE (250 5650);
FORCENOTE
CURRENT LIMIT
(250 5716) 0;
DISPLAY LEFT (250 5716);
DISPLAY 1.021277 (250 5716);
PAINT WHITE (250 5716);
FORCENOTE
PC1320
(-800 3875) 0;
DISPLAY LEFT (-800 3875);
DISPLAY 1.021277 (-800 3875);
FORCENOTE
DE-POP
(-25 4075) 0;
DISPLAY LEFT (-25 4075);
DISPLAY 1.021277 (-25 4075);
FORCENOTE
POP
(25 4175) 0;
DISPLAY LEFT (25 4175);
DISPLAY 1.021277 (25 4175);
FORCENOTE
VIMON(MAX)= 1.582V @ IOUT=9.09A
(-2750 1725) 0;
DISPLAY LEFT (-2750 1725);
DISPLAY 1.021277 (-2750 1725);
PAINT WHITE (-2750 1725);
FORCENOTE
POP
(-450 4075) 0;
DISPLAY LEFT (-450 4075);
DISPLAY 1.021277 (-450 4075);
FORCENOTE
ENABLE:
(-4700 2875) 0;
DISPLAY LEFT (-4700 2875);
DISPLAY 1.021277 (-4700 2875);
PAINT WHITE (-4700 2875);
FORCENOTE
DESIGN SPECIFICATION
(-5416 7494) 0;
DISPLAY LEFT (-5416 7494);
DISPLAY 1.170213 (-5416 7494);
FORCENOTE
IMAX=6.6A
(-5425 6925) 0;
DISPLAY LEFT (-5425 6925);
DISPLAY 1.021277 (-5425 6925);
FORCENOTE
OCP=IMAX*1.3=8.58A
(-5425 6850) 0;
DISPLAY LEFT (-5425 6850);
DISPLAY 1.021277 (-5425 6850);
FORCENOTE
P3V3_OCP_V3_2_R
(-5425 7400) 0;
DISPLAY LEFT (-5425 7400);
DISPLAY 0.936170 (-5425 7400);
FORCENOTE
IMAX=1.1A
(-5425 7325) 0;
DISPLAY LEFT (-5425 7325);
DISPLAY 0.936170 (-5425 7325);
FORCENOTE
OCP=IMAX*1.3=1.43A
(-5425 7250) 0;
DISPLAY LEFT (-5425 7250);
DISPLAY 0.936170 (-5425 7250);
FORCENOTE
TDELAY: 6.29MS
(-4275 2050) 0;
DISPLAY LEFT (-4275 2050);
DISPLAY 1.021277 (-4275 2050);
PAINT WHITE (-4275 2050);
FORCENOTE
TFAULT: 1.27MS
(-4275 2125) 0;
DISPLAY LEFT (-4275 2125);
DISPLAY 1.021277 (-4275 2125);
PAINT WHITE (-4275 2125);
FORCENOTE
MP5022C
(-475 4375) 0;
DISPLAY LEFT (-475 4375);
DISPLAY 1.021277 (-475 4375);
FORCENOTE
POP
(25 4275) 0;
DISPLAY LEFT (25 4275);
DISPLAY 1.021277 (25 4275);
FORCENOTE
DE-POP
(-450 4175) 0;
DISPLAY LEFT (-450 4175);
DISPLAY 1.021277 (-450 4175);
FORCENOTE
DE-POP
(-25 3975) 0;
DISPLAY LEFT (-25 3975);
DISPLAY 1.021277 (-25 3975);
FORCENOTE
MP5025C/
(-475 4425) 0;
DISPLAY LEFT (-475 4425);
DISPLAY 1.021277 (-475 4425);
FORCENOTE
DE-POP
(-450 4275) 0;
DISPLAY LEFT (-450 4275);
DISPLAY 1.021277 (-450 4275);
FORCENOTE
PR3850
(-795 4267) 0;
DISPLAY LEFT (-795 4267);
DISPLAY 1.021277 (-795 4267);
FORCENOTE
PR3853
(-800 4075) 0;
DISPLAY LEFT (-800 4075);
DISPLAY 1.021277 (-800 4075);
FORCENOTE
2ND SOURCE OF PU201
(-2550 4125) 0;
DISPLAY LEFT (-2550 4125);
DISPLAY 1.276596 (-2550 4125);
QUIT
